G04 ================== begin FILE IDENTIFICATION RECORD ==================*
G04 Layout Name:  F:/<user>/2022/FB/R4006-TIMING/brd/gerber-3/R4006-B0001-02_R01.brd*
G04 Film Name:    R4006-B0001-02_R01_L04*
G04 File Format:  Gerber RS274X*
G04 File Origin:  Cadence Allegro 17.2-S079*
G04 Origin Date:  Fri Feb 25 18:14:43 2022*
G04 *
G04 Layer:  ETCH/L04_GND2*
G04 Layer:  PIN/L04_GND2*
G04 Layer:  VIA CLASS/L04_GND2*
G04 Layer:  MANUFACTURING/L04_GND2*
G04 Layer:  MANUFACTURING/CELESTICA_LEGEND*
G04 *
G04 Offset:    (0.00 0.00)*
G04 Mirror:    No*
G04 Mode:      Negative*
G04 Rotation:  0*
G04 FullContactRelief:  No*
G04 UndefLineWidth:     6.00*
G04 ================== end FILE IDENTIFICATION RECORD ====================*
%FSLAX55Y55*MOIN*%
%IR0*IPPOS*OFA0.00000B0.00000*MIA0B0*SFA1.00000B1.00000*%
%AMMACRO17*
4,1,20,-.005,-.04399,
-.009177,-.042751,
-.013075,-.040805,
-.016576,-.038212,
-.019573,-.03505,
-.021977,-.031416,
-.023712,-.02742,
-.024727,-.023183,
-.025,-.0195,
-.025,-.006,
-.02,-.006,
-.02,-.0195,
-.019696,-.022972,
-.018794,-.026338,
-.017321,-.029497,
-.015322,-.032352,
-.012858,-.034816,
-.010003,-.036815,
-.006845,-.038288,
-.005,-.03886,
-.005,-.04399,
270.*
4,1,20,.005,-.04399,
.005,-.03886,
.008286,-.037699,
.01132,-.035985,
.014011,-.033769,
.016276,-.031121,
.018047,-.028119,
.019269,-.024855,
.019907,-.021429,
.02,-.0195,
.02,-.006,
.025,-.006,
.025,-.0195,
.02462,-.02384,
.023493,-.028048,
.021651,-.031997,
.019153,-.035566,
.016072,-.038647,
.012503,-.041145,
.008554,-.042987,
.005,-.04399,
270.*
4,1,20,-.025,.006,
-.025,.0195,
-.02462,.02384,
-.023493,.028048,
-.021651,.031997,
-.019153,.035566,
-.016072,.038647,
-.012503,.041145,
-.008554,.042987,
-.005,.04399,
-.005,.03886,
-.008286,.037699,
-.01132,.035985,
-.014011,.033769,
-.016276,.031121,
-.018047,.028119,
-.019269,.024855,
-.019907,.021429,
-.02,.0195,
-.02,.006,
-.025,.006,
270.*
4,1,20,.02,.006,
.02,.0195,
.019696,.022972,
.018794,.026338,
.017321,.029497,
.015322,.032352,
.012858,.034816,
.010003,.036815,
.006845,.038288,
.005,.03886,
.005,.04399,
.009177,.042751,
.013075,.040805,
.016576,.038212,
.019573,.03505,
.021977,.031416,
.023712,.02742,
.024727,.023183,
.025,.0195,
.025,.006,
.02,.006,
270.*
%
%ADD17MACRO17*%
%ADD22C,.03*%
%ADD16C,.02*%
%ADD12C,.032*%
%ADD14C,.024*%
%ADD20C,.026*%
%ADD21C,.028*%
%ADD15C,.082*%
%ADD10C,.018*%
%ADD19C,.039*%
%ADD28C,.099*%
%AMMACRO24*
4,1,18,.03817,.02827,
.042499,.021212,
.045537,.01351,
.047191,.005398,
.047412,-.002879,
.046191,-.011068,
.043568,-.018921,
.03962,-.026199,
.03817,-.02827,
.04174,-.03184,
.046635,-.024108,
.050113,-.015644,
.052068,-.006704,
.052441,.002439,
.051221,.011508,
.048444,.020228,
.044196,.028333,
.04174,.03184,
.03817,.02827,
0.0*
4,1,18,.02827,-.03817,
.021212,-.042499,
.01351,-.045537,
.005398,-.047191,
-.002879,-.047412,
-.011068,-.046191,
-.018921,-.043568,
-.026199,-.03962,
-.02827,-.03817,
-.03184,-.04174,
-.024108,-.046635,
-.015644,-.050113,
-.006704,-.052068,
.002439,-.052441,
.011508,-.051221,
.020228,-.048444,
.028333,-.044196,
.03184,-.04174,
.02827,-.03817,
0.0*
4,1,18,-.03817,-.02827,
-.042499,-.021212,
-.045537,-.01351,
-.047191,-.005398,
-.047412,.002879,
-.046191,.011068,
-.043568,.018921,
-.03962,.026199,
-.03817,.02827,
-.04174,.03184,
-.046635,.024108,
-.050113,.015644,
-.052068,.006704,
-.052441,-.002439,
-.051221,-.011508,
-.048444,-.020228,
-.044196,-.028333,
-.04174,-.03184,
-.03817,-.02827,
0.0*
4,1,18,-.02827,.03817,
-.021212,.042499,
-.01351,.045537,
-.005398,.047191,
.002879,.047412,
.011068,.046191,
.018921,.043568,
.026199,.03962,
.02827,.03817,
.03184,.04174,
.024108,.046635,
.015644,.050113,
.006704,.052068,
-.002439,.052441,
-.011508,.051221,
-.020228,.048444,
-.028333,.044196,
-.03184,.04174,
-.02827,.03817,
0.0*
%
%ADD24MACRO24*%
%AMMACRO31*
4,1,17,.0205,.01342,
.022519,.009656,
.023854,.005599,
.024464,.001372,
.02433,-.002897,
.023457,-.007078,
.021872,-.011044,
.0205,-.01342,
.02409,-.01702,
.02668,-.012578,
.028458,-.007754,
.029373,-.002695,
.029394,.002447,
.028523,.007514,
.026785,.012353,
.024233,.016816,
.02409,.01702,
.0205,.01342,
90.*
4,1,17,.01342,-.0205,
.009656,-.022519,
.005599,-.023854,
.001372,-.024464,
-.002897,-.02433,
-.007078,-.023457,
-.011044,-.021872,
-.01342,-.0205,
-.01702,-.02409,
-.012578,-.02668,
-.007754,-.028458,
-.002695,-.029373,
.002447,-.029394,
.007514,-.028523,
.012353,-.026785,
.016816,-.024233,
.01702,-.02409,
.01342,-.0205,
90.*
4,1,17,-.0205,-.01342,
-.022519,-.009656,
-.023854,-.005599,
-.024464,-.001372,
-.02433,.002897,
-.023457,.007078,
-.021872,.011044,
-.0205,.01342,
-.02409,.01702,
-.02668,.012578,
-.028458,.007754,
-.029373,.002695,
-.029394,-.002447,
-.028523,-.007514,
-.026785,-.012353,
-.024233,-.016816,
-.02409,-.01702,
-.0205,-.01342,
90.*
4,1,17,-.01342,.0205,
-.009656,.022519,
-.005599,.023854,
-.001372,.024464,
.002897,.02433,
.007078,.023457,
.011044,.021872,
.01342,.0205,
.01702,.02409,
.012578,.02668,
.007754,.028458,
.002695,.029373,
-.002447,.029394,
-.007514,.028523,
-.012353,.026785,
-.016816,.024233,
-.01702,.02409,
-.01342,.0205,
90.*
%
%ADD31MACRO31*%
%AMMACRO26*
4,1,18,.07318,.05409,
.081461,.040561,
.087267,.025799,
.090421,.010253,
.090828,-.005604,
.088475,-.021291,
.083433,-.036331,
.075857,-.050267,
.07318,-.05409,
.07675,-.05766,
.085597,-.043457,
.091842,-.027933,
.095297,-.01156,
.095857,.005164,
.093504,.021731,
.08831,.037637,
.080433,.052401,
.07675,.05766,
.07318,.05409,
0.0*
4,1,18,.05409,-.07318,
.040561,-.081461,
.025799,-.087267,
.010253,-.090421,
-.005604,-.090828,
-.021291,-.088475,
-.036331,-.083433,
-.050267,-.075857,
-.05409,-.07318,
-.05766,-.07675,
-.043457,-.085597,
-.027933,-.091842,
-.01156,-.095297,
.005164,-.095857,
.021731,-.093504,
.037637,-.08831,
.052401,-.080433,
.05766,-.07675,
.05409,-.07318,
0.0*
4,1,18,-.07318,-.05409,
-.081461,-.040561,
-.087267,-.025799,
-.090421,-.010253,
-.090828,.005604,
-.088475,.021291,
-.083433,.036331,
-.075857,.050267,
-.07318,.05409,
-.07675,.05766,
-.085597,.043457,
-.091842,.027933,
-.095297,.01156,
-.095857,-.005164,
-.093504,-.021731,
-.08831,-.037637,
-.080433,-.052401,
-.07675,-.05766,
-.07318,-.05409,
0.0*
4,1,18,-.05409,.07318,
-.040561,.081461,
-.025799,.087267,
-.010253,.090421,
.005604,.090828,
.021291,.088475,
.036331,.083433,
.050267,.075857,
.05409,.07318,
.05766,.07675,
.043457,.085597,
.027933,.091842,
.01156,.095297,
-.005164,.095857,
-.021731,.093504,
-.037637,.08831,
-.052401,.080433,
-.05766,.07675,
-.05409,.07318,
0.0*
%
%ADD26MACRO26*%
%AMMACRO11*
4,1,18,.03185,.02336,
.035423,.017474,
.037919,.011058,
.039263,.004305,
.039414,-.002578,
.038368,-.009383,
.036155,-.015903,
.032845,-.02194,
.03185,-.02336,
.03542,-.02694,
.03956,-.02038,
.042498,-.013201,
.044145,-.005621,
.04445,.00213,
.043405,.009817,
.041041,.017205,
.03743,.02407,
.03542,.02694,
.03185,.02336,
0.0*
4,1,18,.02336,-.03185,
.017474,-.035423,
.011058,-.037919,
.004305,-.039263,
-.002578,-.039414,
-.009383,-.038368,
-.015903,-.036155,
-.02194,-.032845,
-.02336,-.03185,
-.02694,-.03542,
-.02038,-.03956,
-.013201,-.042498,
-.005621,-.044145,
.00213,-.04445,
.009817,-.043405,
.017205,-.041041,
.02407,-.03743,
.02694,-.03542,
.02336,-.03185,
0.0*
4,1,18,-.03185,-.02336,
-.035423,-.017474,
-.037919,-.011058,
-.039263,-.004305,
-.039414,.002578,
-.038368,.009383,
-.036155,.015903,
-.032845,.02194,
-.03185,.02336,
-.03542,.02694,
-.03956,.02038,
-.042498,.013201,
-.044145,.005621,
-.04445,-.00213,
-.043405,-.009817,
-.041041,-.017205,
-.03743,-.02407,
-.03542,-.02694,
-.03185,-.02336,
0.0*
4,1,18,-.02336,.03185,
-.017474,.035423,
-.011058,.037919,
-.004305,.039263,
.002578,.039414,
.009383,.038368,
.015903,.036155,
.02194,.032845,
.02336,.03185,
.02694,.03542,
.02038,.03956,
.013201,.042498,
.005621,.044145,
-.00213,.04445,
-.009817,.043405,
-.017205,.041041,
-.02407,.03743,
-.02694,.03542,
-.02336,.03185,
0.0*
%
%ADD11MACRO11*%
%AMMACRO30*
4,1,20,-.005,-.03799,
-.009177,-.036751,
-.013075,-.034805,
-.016576,-.032212,
-.019573,-.02905,
-.021977,-.025416,
-.023712,-.02142,
-.024727,-.017183,
-.025,-.0135,
-.025,-.005,
-.02,-.005,
-.02,-.0135,
-.019696,-.016972,
-.018794,-.020338,
-.017321,-.023497,
-.015322,-.026352,
-.012858,-.028816,
-.010003,-.030815,
-.006845,-.032288,
-.005,-.03286,
-.005,-.03799,
90.*
4,1,20,.005,-.03799,
.005,-.03286,
.008286,-.031699,
.01132,-.029985,
.014011,-.027769,
.016276,-.025121,
.018047,-.022119,
.019269,-.018855,
.019907,-.015429,
.02,-.0135,
.02,-.005,
.025,-.005,
.025,-.0135,
.02462,-.01784,
.023493,-.022048,
.021651,-.025997,
.019153,-.029566,
.016072,-.032647,
.012503,-.035145,
.008554,-.036987,
.005,-.03799,
90.*
4,1,20,-.025,.005,
-.025,.0135,
-.02462,.01784,
-.023493,.022048,
-.021651,.025997,
-.019153,.029566,
-.016072,.032647,
-.012503,.035145,
-.008554,.036987,
-.005,.03799,
-.005,.03286,
-.008286,.031699,
-.01132,.029985,
-.014011,.027769,
-.016276,.025121,
-.018047,.022119,
-.019269,.018855,
-.019907,.015429,
-.02,.0135,
-.02,.005,
-.025,.005,
90.*
4,1,20,.02,.005,
.02,.0135,
.019696,.016972,
.018794,.020338,
.017321,.023497,
.015322,.026352,
.012858,.028816,
.010003,.030815,
.006845,.032288,
.005,.03286,
.005,.03799,
.009177,.036751,
.013075,.034805,
.016576,.032212,
.019573,.02905,
.021977,.025416,
.023712,.02142,
.024727,.017183,
.025,.0135,
.025,.005,
.02,.005,
90.*
%
%ADD30MACRO30*%
%ADD23C,.102*%
%ADD13C,.15*%
%ADD29C,.143*%
%ADD25C,.125*%
%AMMACRO18*
4,1,15,.01428,.00721,
.015315,.004621,
.015885,.001891,
.015972,-.000896,
.015574,-.003656,
.014702,-.006305,
.01428,-.00721,
.01796,-.01089,
.019578,-.007606,
.020601,-.004091,
.020999,-.000451,
.020758,.003202,
.019887,.006758,
.018411,.010109,
.01796,.01089,
.01428,.00721,
270.*
4,1,15,.00721,-.01428,
.004621,-.015315,
.001891,-.015885,
-.000896,-.015972,
-.003656,-.015574,
-.006305,-.014702,
-.00721,-.01428,
-.01089,-.01796,
-.007606,-.019578,
-.004091,-.020601,
-.000451,-.020999,
.003202,-.020758,
.006758,-.019887,
.010109,-.018411,
.01089,-.01796,
.00721,-.01428,
270.*
4,1,15,-.01428,-.00721,
-.015315,-.004621,
-.015885,-.001891,
-.015972,.000896,
-.015574,.003656,
-.014702,.006305,
-.01428,.00721,
-.01796,.01089,
-.019578,.007606,
-.020601,.004091,
-.020999,.000451,
-.020758,-.003202,
-.019887,-.006758,
-.018411,-.010109,
-.01796,-.01089,
-.01428,-.00721,
270.*
4,1,15,-.00721,.01428,
-.004621,.015315,
-.001891,.015885,
.000896,.015972,
.003656,.015574,
.006305,.014702,
.00721,.01428,
.01089,.01796,
.007606,.019578,
.004091,.020601,
.000451,.020999,
-.003202,.020758,
-.006758,.019887,
-.010109,.018411,
-.01089,.01796,
-.00721,.01428,
270.*
%
%ADD18MACRO18*%
%AMMACRO27*
4,1,18,.0371,.0272,
.04126,.020344,
.044166,.012871,
.04573,.005006,
.045904,-.003011,
.044684,-.010936,
.042106,-.01853,
.038249,-.02556,
.0371,-.0272,
.04067,-.03077,
.045395,-.02324,
.048741,-.015004,
.050606,-.006313,
.050934,.002571,
.049713,.011376,
.046983,.019836,
.042824,.027693,
.04067,.03077,
.0371,.0272,
270.*
4,1,18,.0272,-.0371,
.020344,-.04126,
.012871,-.044166,
.005006,-.04573,
-.003011,-.045904,
-.010936,-.044684,
-.01853,-.042106,
-.02556,-.038249,
-.0272,-.0371,
-.03077,-.04067,
-.02324,-.045395,
-.015004,-.048741,
-.006313,-.050606,
.002571,-.050934,
.011376,-.049713,
.019836,-.046983,
.027693,-.042824,
.03077,-.04067,
.0272,-.0371,
270.*
4,1,18,-.0371,-.0272,
-.04126,-.020344,
-.044166,-.012871,
-.04573,-.005006,
-.045904,.003011,
-.044684,.010936,
-.042106,.01853,
-.038249,.02556,
-.0371,.0272,
-.04067,.03077,
-.045395,.02324,
-.048741,.015004,
-.050606,.006313,
-.050934,-.002571,
-.049713,-.011376,
-.046983,-.019836,
-.042824,-.027693,
-.04067,-.03077,
-.0371,-.0272,
270.*
4,1,18,-.0272,.0371,
-.020344,.04126,
-.012871,.044166,
-.005006,.04573,
.003011,.045904,
.010936,.044684,
.01853,.042106,
.02556,.038249,
.0272,.0371,
.03077,.04067,
.02324,.045395,
.015004,.048741,
.006313,.050606,
-.002571,.050934,
-.011376,.049713,
-.019836,.046983,
-.027693,.042824,
-.03077,.04067,
-.0272,.0371,
270.*
%
%ADD27MACRO27*%
%ADD32C,.01*%
%ADD33C,.005*%
%ADD34C,.006*%
%ADD36R,.07002X.03002*%
%ADD38R,.07004X.03002*%
%ADD35R,.07002X.03004*%
%ADD49C,.40006*%
%ADD48R,.07004X.03004*%
%ADD40R,.03004X.07004*%
%ADD37R,.02802X.06002*%
%ADD43C,.12406*%
%ADD47R,.06002X.02804*%
%ADD41R,.02802X.06004*%
%ADD39R,.06004X.02802*%
%ADD46R,.06004X.02804*%
%ADD42C,.14906*%
%ADD45O,.02606X.06543*%
%ADD44C,.16806*%
G75*
%LPD*%
G75*
G36*
G01X-10000Y-10000D02*
X670039D01*
Y447598D01*
X-10000D01*
Y-10000D01*
G37*
%LPC*%
G75*
G36*
G01X309201Y26200D02*
X231744D01*
Y29331D01*
G03X218256I-6744J0D01*
G01Y26200D01*
X180169D01*
Y43012D01*
G03X159791I-10189J0D01*
G01Y21654D01*
G02X158858Y20721I-933J0D01*
G01X135236D01*
G02X134303Y21654I0J933D01*
G01Y46260D01*
G03X127362Y53201I-6941J0D01*
G01X62992D01*
G03X56051Y46260I0J-6941D01*
G01Y21654D01*
G02X55118Y20721I-933J0D01*
G01X3937D01*
G02X3004Y21654I0J933D01*
G01Y433661D01*
G02X3937Y434594I933J0D01*
G01X656102D01*
G02X657035Y433661I0J-933D01*
G01Y287647D01*
G03X652239Y282678I177J-4969D01*
G01Y241437D01*
G03X657035Y236468I4972J0D01*
G01Y54134D01*
G02X656102Y53201I-933J0D01*
G01X316142D01*
G03X309201Y46260I0J-6941D01*
G01Y26200D01*
G37*
%LPD*%
G75*
G36*
G01X600696Y115350D02*
G02X617500Y124503I16804J-10849D01*
G02X637503Y104500I0J-20003D01*
G02X636283Y97621I-20004J0D01*
G02X636500Y96501I-2783J-1120D01*
G01Y96500D01*
G02X634273Y93601I-3000J0D01*
G02X617500Y84497I-16773J10899D01*
G02X597497Y104500I0J20003D01*
G02X598437Y110560I20003J0D01*
G02X597846Y112349I2413J1789D01*
G01Y112350D01*
G02X600696Y115350I3004J0D01*
G37*
G36*
G01X395067Y171866D02*
X399004D01*
G02Y169262I0J-1302D01*
G01X395067D01*
G02Y171866I0J1302D01*
G37*
G36*
G01X402942Y167930D02*
X406879D01*
G02Y165324I0J-1303D01*
G01X402942D01*
G02Y167930I0J1303D01*
G37*
G36*
G01X387193D02*
X391130D01*
G02Y165324I0J-1303D01*
G01X387193D01*
G02Y167930I0J1303D01*
G37*
G36*
G01X395067Y163992D02*
X399004D01*
G02Y161388I0J-1302D01*
G01X395067D01*
G02Y163992I0J1302D01*
G37*
G36*
G01X446248Y185008D02*
X442311D01*
G02Y187614I0J1303D01*
G01X446248D01*
G02Y185008I0J-1303D01*
G37*
G36*
G01X461996Y132496D02*
X465933D01*
G02Y129890I0J-1303D01*
G01X461996D01*
G02Y132496I0J1303D01*
G37*
G36*
G01X446248Y141702D02*
G02Y144308I0J1303D01*
G01X450185D01*
G02Y141702I0J-1303D01*
G01X446248D01*
G37*
G36*
G01X387193Y157450D02*
G02Y160056I0J1303D01*
G01X391130D01*
G02Y157450I0J-1303D01*
G01X387193D01*
G37*
G36*
G01X402942Y149576D02*
G02Y152182I0J1303D01*
G01X406879D01*
G02Y149576I0J-1303D01*
G01X402942D01*
G37*
G36*
G01X310516Y87500D02*
X312500Y89484D01*
X316747Y85237D01*
X314763Y83253D01*
X310516Y87500D01*
G37*
G36*
G01X395067Y153514D02*
G02Y156118I0J1302D01*
G01X399004D01*
G02Y153514I0J-1302D01*
G01X395067D01*
G37*
G36*
G01X387193Y149576D02*
G02Y152182I0J1303D01*
G01X391130D01*
G02Y149576I0J-1303D01*
G01X387193D01*
G37*
G36*
G01X395067Y145640D02*
G02Y148244I0J1302D01*
G01X399004D01*
G02Y145640I0J-1302D01*
G01X395067D01*
G37*
G36*
G01X387193Y141702D02*
G02Y144308I0J1303D01*
G01X391130D01*
G02Y141702I0J-1303D01*
G01X387193D01*
G37*
G36*
G01X469870Y145640D02*
G02Y148244I0J1302D01*
G01X473807D01*
G02Y145640I0J-1302D01*
G01X469870D01*
G37*
G54D36*
X455731Y122167D03*
X439251Y116599D03*
X353065Y104707D03*
G54D38*
X403250Y116099D03*
G54D35*
X281801Y198700D03*
G54D49*
X599000Y209400D03*
G54D48*
X343400Y108500D03*
G54D40*
X284500Y185900D03*
X240508Y71500D03*
X337500Y117800D03*
G54D37*
X345301Y191499D03*
X365101Y189959D03*
G54D43*
X268567Y255943D03*
X146067Y268043D03*
X143567Y106043D03*
X268567Y112143D03*
G54D47*
X268307Y76300D03*
X283455D03*
G54D41*
X264339Y36900D03*
X295835D03*
X280087D03*
X295835Y46500D03*
X619961Y226074D03*
G54D39*
X324310Y190299D03*
G54D46*
X71900Y357500D03*
X108900Y382500D03*
X248622Y76300D03*
X364100Y92000D03*
G54D42*
X640039Y65354D03*
X29528Y373031D03*
Y36811D03*
X640039Y417835D03*
G54D45*
X473807Y137098D03*
G54D44*
X634055Y334449D03*
Y367519D03*
G54D17*
X24807Y335985D03*
Y347245D03*
X43705Y331655D03*
Y351576D03*
G54D22*
X76100Y154400D03*
X75950Y164200D03*
X73600Y252500D03*
X68600Y274000D03*
X75500Y282500D03*
X63800Y274000D03*
X70500Y419000D03*
X75580Y419004D03*
X88300Y163900D03*
X98000Y420000D03*
X90000Y420500D03*
X85500D03*
X112880Y73020D03*
X126000Y67000D03*
Y62000D03*
X131500Y290500D03*
X148500Y62500D03*
X139500D03*
X145900Y75200D03*
X142070Y77900D03*
X142000Y69535D03*
X136000Y290500D03*
X138250Y372250D03*
X148500Y376000D03*
X138500Y387500D03*
X153500Y390500D03*
X163300Y382900D03*
X151100Y386300D03*
X152100Y399300D03*
X151530Y406300D03*
X153150Y394590D03*
X160600Y417400D03*
X152200Y416300D03*
X183170Y56390D03*
X180620Y77890D03*
X180390Y70720D03*
X180910Y63390D03*
X187598Y36900D03*
X189500Y33000D03*
X186000D03*
X187598Y28900D03*
X191535Y41200D03*
X198135Y36500D03*
X195000Y54550D03*
X203000Y75000D03*
X196497Y76502D03*
X210500Y30500D03*
X207880Y78740D03*
X214810Y78810D03*
X212800Y289500D03*
X218500Y301700D03*
X213500D03*
X208500D03*
X224500Y302000D03*
X222000Y330000D03*
X254527Y33900D03*
X240508Y69900D03*
Y73100D03*
X263300Y52200D03*
X284500Y184300D03*
Y187500D03*
X283400Y198700D03*
X280200D03*
X289600Y330100D03*
X307300Y61300D03*
X298700Y327000D03*
Y323500D03*
X293200Y329500D03*
X322200Y320500D03*
X310600Y335000D03*
X322200Y338500D03*
X341799Y108500D03*
X337500Y116200D03*
Y119400D03*
X349000Y82500D03*
X344999Y108500D03*
X351464Y104707D03*
X354664D03*
X352300Y175000D03*
X358400Y182700D03*
X345930Y217000D03*
X354800Y285600D03*
X355000Y328000D03*
X375500Y350500D03*
X380400Y81600D03*
X381700Y92400D03*
X383128Y178372D03*
X383000Y346600D03*
X388500Y391000D03*
X393500D03*
X388500Y400000D03*
X393500D03*
X393000Y418500D03*
X401650Y116099D03*
X404850D03*
X405463Y383000D03*
X410463D03*
X398500Y391000D03*
Y400000D03*
X403000Y418500D03*
X398000D03*
X415463Y383000D03*
X414000Y419000D03*
X422337Y424000D03*
X416800D03*
X437650Y116599D03*
X440850D03*
X442500Y336089D03*
X439500Y341500D03*
X443000Y386500D03*
X432000Y396500D03*
X457330Y122167D03*
X454130D03*
X490970Y133500D03*
Y138500D03*
X488500Y359000D03*
X500500Y271100D03*
X500000Y278799D03*
X533000Y95000D03*
Y99500D03*
X522400Y270700D03*
X522600Y276200D03*
X528500Y299000D03*
X532300Y425700D03*
X549500Y69400D03*
X548158Y228033D03*
X545250Y256300D03*
X539977Y275124D03*
X540318Y270436D03*
X537500Y296607D03*
X568600Y76000D03*
X553122Y227979D03*
X559500Y228000D03*
X566700Y227500D03*
X552000Y367597D03*
Y371141D03*
X555200Y367597D03*
Y371141D03*
X552000Y374684D03*
Y378227D03*
X555200D03*
Y374684D03*
X572500Y60301D03*
X572870Y67570D03*
X577100Y227900D03*
X581400Y262100D03*
Y272100D03*
Y282100D03*
X581500Y302100D03*
X576200Y342500D03*
X597000Y199900D03*
X591902Y200300D03*
X601902Y200100D03*
X594153Y220500D03*
X589953Y236600D03*
X591000Y261500D03*
X590500Y301500D03*
X606902Y200400D03*
X633500Y205906D03*
X625800Y215874D03*
X633000Y267000D03*
G54D12*
X11264Y152264D03*
X9000Y279000D03*
Y286000D03*
X12500Y91000D03*
Y96000D03*
Y101000D03*
Y106000D03*
X19100Y148798D03*
X23600D03*
X28100D03*
X13620Y148720D03*
X13000Y157000D03*
X12500Y162000D03*
Y209500D03*
Y204500D03*
Y214500D03*
Y219500D03*
X11963Y266437D03*
X19000Y262500D03*
X24200Y262508D03*
X28700D03*
X12500Y261500D03*
X15000Y279000D03*
X28700Y274300D03*
X13000Y273327D03*
X28500Y302000D03*
X28000Y296500D03*
X16000Y297500D03*
X24100Y310900D03*
X18000Y314500D03*
X13000Y318700D03*
X11976Y323524D03*
X28000Y327000D03*
X44500Y73500D03*
X45500Y104390D03*
X41500Y127500D03*
X41409Y132591D03*
X41600Y148798D03*
X32600Y148700D03*
X37100Y148798D03*
X45500Y182500D03*
X45000Y213000D03*
X46000Y219500D03*
X40500Y262000D03*
X33200Y262508D03*
X43000Y255500D03*
X37400Y282900D03*
X29000Y291500D03*
X43000Y314500D03*
X33000D03*
X44500Y309000D03*
X39500D03*
X34500D03*
X35500Y327000D03*
X59600Y60200D03*
X55500Y59000D03*
X50500Y60228D03*
X60100Y73000D03*
X57000Y83500D03*
X51500D03*
X50500Y104800D03*
X59000Y96500D03*
X62500Y100500D03*
X57500Y101500D03*
X62500Y117000D03*
X48390Y128312D03*
X53740Y126000D03*
X55922Y140543D03*
X46500Y133000D03*
X47500Y140500D03*
X60500Y152000D03*
X51400Y161600D03*
X54130Y152500D03*
X60600Y157000D03*
X48957Y153619D03*
X53500Y183500D03*
X58000Y213500D03*
X54000D03*
X48000Y200500D03*
X53000D03*
X63000Y206000D03*
Y210500D03*
Y215000D03*
X49600Y213455D03*
X51452Y219900D03*
X53200Y240187D03*
X54590Y266870D03*
X48232Y264530D03*
X48500Y252500D03*
X55200Y253500D03*
X52500Y278000D03*
X52800Y272000D03*
X62000Y307000D03*
Y323500D03*
X55000Y336000D03*
Y355400D03*
X62500Y365000D03*
Y369000D03*
Y373000D03*
Y378000D03*
Y382000D03*
X60300Y407100D03*
Y401100D03*
Y395100D03*
Y413100D03*
X71500Y77000D03*
X76400Y87200D03*
X76321Y78300D03*
X78500Y82250D03*
X73500Y112500D03*
X67000Y109000D03*
X79000Y100500D03*
X74000D03*
X67500Y114500D03*
X68000Y119000D03*
X73500D03*
X69500Y130000D03*
X74000D03*
X75000Y141700D03*
X64445Y168945D03*
X69000Y187500D03*
Y193000D03*
X69023Y198524D03*
X67400Y227100D03*
X71400Y232900D03*
X68000Y235500D03*
X67700Y240200D03*
X72400Y264600D03*
X69500Y257800D03*
X64248Y258000D03*
X64500Y296750D03*
X78000Y291500D03*
X66000Y318500D03*
X79000Y315500D03*
X66000Y323500D03*
X78635Y324492D03*
X79500Y341790D03*
Y348500D03*
X72000Y346300D03*
X73000Y365000D03*
X69500D03*
X66000D03*
X66500Y382000D03*
X70500D03*
X80700Y399200D03*
Y404200D03*
X71300D03*
Y399200D03*
X76000D03*
Y404200D03*
X71300Y394200D03*
X76000D03*
X80700D03*
X64300Y407600D03*
Y401600D03*
Y395600D03*
X80500Y420500D03*
X80700Y409200D03*
X76000D03*
X71300D03*
X64300Y413600D03*
X86000Y63100D03*
X84200Y75000D03*
X82100Y79300D03*
X96500Y98000D03*
X92250Y97750D03*
X89000Y110500D03*
X93500D03*
X90500Y105000D03*
X84000Y100500D03*
X87000Y130000D03*
Y120000D03*
X93500Y125000D03*
X87000Y125500D03*
X93500Y130000D03*
X90500Y144500D03*
X95500Y145500D03*
X96500Y140000D03*
X91500D03*
X88400Y154900D03*
X93900Y155200D03*
X95200Y151000D03*
X88500Y149000D03*
X94500Y163000D03*
X98500Y159000D03*
X91000Y181500D03*
X88250Y177250D03*
X83500Y178000D03*
X97500Y172000D03*
X98500Y165500D03*
X92000Y173000D03*
X83500D03*
X95500Y192000D03*
X83500Y193000D03*
Y188500D03*
X90500D03*
X94500Y197000D03*
X90500Y193500D03*
X97500Y214000D03*
X84500Y218000D03*
X95700Y227500D03*
X98500Y218500D03*
X96000Y241000D03*
X85700Y236500D03*
X96500Y235500D03*
X98500Y256661D03*
X83200Y260300D03*
X86900Y267200D03*
X95900Y278900D03*
X94500Y312500D03*
X95000Y321500D03*
X82500Y339000D03*
X82951Y327940D03*
X97500Y341000D03*
X95100Y351900D03*
X83000Y352500D03*
Y344500D03*
X95000D03*
X82800Y364600D03*
X94500Y373000D03*
Y369000D03*
Y364500D03*
X90500D03*
X86500D03*
X91500Y359500D03*
X83500Y360000D03*
X82800Y384600D03*
X94500Y380500D03*
X94000Y384500D03*
X90500D03*
X86500D03*
X94500Y376500D03*
X85400Y404200D03*
Y399200D03*
Y394200D03*
X96800Y408100D03*
X92800D03*
Y402100D03*
X96800D03*
Y396100D03*
X92800D03*
X85400Y409200D03*
X96800Y414100D03*
X92800D03*
X111330Y59810D03*
X99000Y175500D03*
Y188500D03*
Y197500D03*
Y206500D03*
Y201500D03*
Y260025D03*
X112500Y302000D03*
X107500D03*
X112500Y290000D03*
X102500D03*
Y302000D03*
X105410Y318500D03*
X115253Y306247D03*
X101500Y341000D03*
X104019Y347425D03*
X103000Y351500D03*
X113000Y344500D03*
X114000Y352000D03*
X104500Y377000D03*
X125000Y76500D03*
X126000Y72000D03*
X117500Y290000D03*
X129000Y321500D03*
X126000Y318000D03*
X129500Y328000D03*
X130000Y349664D03*
X119000Y352000D03*
X124500D03*
X140100Y306900D03*
X135000Y312000D03*
X149500Y311034D03*
X140700Y320000D03*
X146000Y334000D03*
X141916Y333916D03*
X137000Y364000D03*
X145000Y359000D03*
X141000Y379500D03*
X148500Y380000D03*
X145000Y378000D03*
X135200Y408400D03*
X140000Y401000D03*
X135100Y412600D03*
X143500Y418000D03*
X153270Y58400D03*
X151200Y75191D03*
X160500Y75500D03*
Y71500D03*
X156800Y301100D03*
X156600Y295000D03*
X156000Y320500D03*
Y316500D03*
Y325000D03*
Y329000D03*
X159100Y354600D03*
X166700Y343800D03*
X151500Y358000D03*
X159100Y382600D03*
X163600Y378600D03*
X157900Y387400D03*
X158500Y405200D03*
X160582Y410000D03*
X160550Y413400D03*
X151700Y411300D03*
X173170Y70840D03*
X182600Y289500D03*
X179500Y294600D03*
X176500Y290000D03*
X178000Y309500D03*
X173800Y324100D03*
X175000Y394500D03*
X177000Y398000D03*
X188900Y54960D03*
X195900Y332500D03*
X213500Y54000D03*
X208160Y73990D03*
X204770Y67780D03*
X207800Y83010D03*
X219200Y338800D03*
X205000Y348800D03*
Y353800D03*
X215000Y343800D03*
X219000Y348800D03*
Y392500D03*
X215500D03*
X216500Y396000D03*
X220000D03*
X223500Y58250D03*
X231000Y68000D03*
Y71500D03*
X228500Y75500D03*
Y79000D03*
X226500Y334000D03*
X222500Y324500D03*
X238000Y345000D03*
X225500Y347500D03*
X230000D03*
X249000Y290300D03*
X255400Y290100D03*
X247000Y344500D03*
X251000D03*
X255000D03*
X259500Y54700D03*
X259000Y344500D03*
X296400Y70200D03*
X307500Y160500D03*
X303500Y164000D03*
X298284Y175184D03*
X300995Y187611D03*
X297772Y188694D03*
X297000Y310500D03*
X301000Y317000D03*
X293700Y317300D03*
X309000Y164500D03*
X312500Y160500D03*
X320500Y170000D03*
X324000Y227500D03*
Y220750D03*
X312500Y225400D03*
X311900Y229900D03*
Y243400D03*
X312000Y269000D03*
Y256500D03*
Y264500D03*
X317500Y295500D03*
X321000D03*
X324500D03*
X310500Y321000D03*
X312500Y307500D03*
X310600Y326000D03*
X325000Y363000D03*
X320000Y398500D03*
X323000Y401500D03*
X336000Y61060D03*
X340500Y63500D03*
Y87000D03*
X338000Y102500D03*
X332550Y213550D03*
X327923Y221577D03*
X335153Y217875D03*
X333500Y258900D03*
X338500Y259000D03*
X339500Y282000D03*
X341000Y304000D03*
X332500Y306500D03*
X328000D03*
X341400Y323500D03*
X340500Y361300D03*
X332500D03*
X336500D03*
X339200Y380300D03*
X339300Y384000D03*
Y387700D03*
X340500Y391600D03*
X336300Y423200D03*
Y415200D03*
Y419200D03*
X340800Y415200D03*
X349500Y61000D03*
X354500Y60920D03*
X345500Y87000D03*
X354000Y82500D03*
X344000Y103000D03*
X347500Y141500D03*
X350000D03*
X352500D03*
X355000D03*
X357000Y154200D03*
X353482Y154157D03*
X350085Y154300D03*
X346500Y174000D03*
X344500Y181500D03*
X349128Y186628D03*
X344000Y212000D03*
X355500Y218000D03*
Y220500D03*
Y225500D03*
Y223000D03*
X351000Y233243D03*
Y237000D03*
X352500Y260000D03*
X348500D03*
X357680Y271780D03*
X357000Y295500D03*
X356000Y302300D03*
X349000Y295500D03*
X346000Y306500D03*
X351000Y308000D03*
X355000Y337000D03*
X348418Y361300D03*
X344500D03*
X347700Y381600D03*
X347000Y391200D03*
X359800Y397700D03*
X347600Y398800D03*
X348279Y405678D03*
X353000Y416500D03*
X350000Y419500D03*
X349500Y415000D03*
X346000Y416000D03*
X343700Y409900D03*
X348863Y410500D03*
X369310Y109500D03*
X369172Y102828D03*
X362000Y123500D03*
Y128000D03*
X376500Y141000D03*
X374000D03*
X360500Y154500D03*
X374900Y154228D03*
X371400Y154300D03*
X367900Y154228D03*
X367400Y174400D03*
X373649Y185735D03*
X377500Y218500D03*
Y221000D03*
Y226500D03*
Y223500D03*
X373500Y247000D03*
X365500Y246500D03*
X375800Y255200D03*
X376500Y269000D03*
X365000Y268000D03*
X370000Y276000D03*
X374500D03*
X361400Y301500D03*
Y305800D03*
Y309900D03*
X365500Y305900D03*
X375500Y309200D03*
X371000Y326000D03*
X370000Y337000D03*
Y332500D03*
X366000Y350850D03*
X360700Y406200D03*
X364500Y413500D03*
X382286Y86214D03*
X379000Y141000D03*
X382000Y142000D03*
X378400Y154300D03*
X384091Y200091D03*
X379500Y237500D03*
X391900Y246800D03*
X386000D03*
X380100D03*
X386000Y259250D03*
X389400Y281100D03*
X378000Y281000D03*
X382200D03*
X394800Y281300D03*
X383000Y323500D03*
X390000Y338500D03*
X392500Y329100D03*
Y323900D03*
X381000Y365000D03*
X386500D03*
X389500Y370000D03*
X395000D03*
Y360000D03*
X383900Y384600D03*
X379500Y381000D03*
Y375800D03*
Y417500D03*
X407500Y225000D03*
X397800Y246800D03*
X403700D03*
X409300D03*
X400000Y265500D03*
X402000Y303000D03*
X396981Y304482D03*
X407500Y300500D03*
X402500Y308000D03*
X408500Y316500D03*
Y321998D03*
Y311000D03*
X398000Y336500D03*
X410000Y338000D03*
X406610Y353410D03*
X411840Y353620D03*
X409000Y371339D03*
X423000Y72950D03*
X417500Y75000D03*
X425000Y87700D03*
X420900Y246800D03*
X415000D03*
X420900Y259000D03*
X424900Y284300D03*
X423900Y278500D03*
X424900Y292900D03*
X413000Y300500D03*
X429442Y310075D03*
X417500Y337000D03*
X422500Y354500D03*
X428500Y346000D03*
X413500Y373500D03*
X419000D03*
X420500Y366000D03*
X425000Y381000D03*
X420500D03*
X423500Y415500D03*
X436500Y233000D03*
X443500Y231500D03*
X436500Y237500D03*
X439500Y250000D03*
X435000Y250500D03*
X443500Y236500D03*
X440000Y278500D03*
X434600Y278300D03*
X435500Y274500D03*
X445600Y278300D03*
X438150Y283800D03*
X447000Y283000D03*
X433050Y291400D03*
X446000Y294000D03*
X439000Y302000D03*
X434500D03*
X433000Y314320D03*
X435143Y306643D03*
X447000Y321998D03*
X440000Y332500D03*
X434000Y328000D03*
X433000Y353500D03*
X433500Y366500D03*
X433382Y360466D03*
X438500Y364500D03*
X438400Y382400D03*
X430000Y381000D03*
X431000Y406500D03*
Y411500D03*
X460000Y76000D03*
X463500Y92000D03*
X458500Y86500D03*
X448500Y100500D03*
X462500Y117000D03*
X461000Y234500D03*
X457500Y227500D03*
Y223500D03*
X449000Y232500D03*
Y227500D03*
X461000Y230000D03*
X448500Y237500D03*
X457500Y250000D03*
X448500D03*
X457500Y237400D03*
X453000Y250000D03*
X457000Y258500D03*
X459500Y262000D03*
X461500Y268409D03*
X460800Y294200D03*
X461000Y302500D03*
X464500Y298500D03*
X456500Y305500D03*
X454000Y312500D03*
X448500Y311500D03*
X461500Y311000D03*
X451000Y306500D03*
X450900Y330900D03*
X450500Y368500D03*
X453500Y381500D03*
X450000Y416500D03*
Y411500D03*
X478000Y78000D03*
X482000Y83500D03*
X465500Y78500D03*
X475500Y82500D03*
X470500D03*
X481000Y172500D03*
X479246Y178464D03*
X477500Y170500D03*
X481500Y193000D03*
X480288Y203788D03*
X471000Y239000D03*
X477000D03*
X468500Y264500D03*
Y270000D03*
X478500Y346000D03*
X481000Y341000D03*
X470500Y391000D03*
X493700Y79161D03*
X496000Y85000D03*
Y163000D03*
X484000Y166000D03*
X497000Y175000D03*
X485033Y174934D03*
X498060Y185500D03*
X483871Y198241D03*
X496500Y197500D03*
X484000Y185500D03*
X497500Y214000D03*
X485000Y202739D03*
X490500Y216750D03*
X492500Y226000D03*
X497500D03*
X497100Y244700D03*
X497200Y240600D03*
X492300Y240800D03*
X497000Y341000D03*
X495000Y346000D03*
X483501D03*
X488500D03*
X504000Y64500D03*
X508500D03*
X513200Y66000D03*
X503005Y99494D03*
X508000Y105500D03*
Y110500D03*
Y115500D03*
X503860Y124150D03*
X503900Y128690D03*
X514500Y144000D03*
X503950Y133500D03*
X514500Y151000D03*
Y148000D03*
Y154000D03*
Y157000D03*
X501500Y192500D03*
X507000D03*
Y188500D03*
X515500Y201000D03*
X513000Y210500D03*
X511500Y206500D03*
X513500Y215500D03*
X509000D03*
X502200Y240700D03*
X501000Y263500D03*
X509000Y340500D03*
X504500D03*
X514000Y374000D03*
X507500Y394500D03*
X503500D03*
X521500Y60000D03*
X529500Y60500D03*
X526500Y67500D03*
X519500Y75500D03*
X533000Y82000D03*
X519500Y81500D03*
X520000Y87000D03*
X524900Y99000D03*
X522500Y114500D03*
X528710Y227500D03*
X534000Y231500D03*
X525400Y247000D03*
X522000D03*
X524300Y261700D03*
X523900Y257100D03*
X523600Y281100D03*
X531000Y285500D03*
X526000Y295500D03*
X519000Y307500D03*
X517500Y374000D03*
X518000Y382500D03*
X527500Y389100D03*
X532100Y399000D03*
X527500Y397100D03*
Y393100D03*
X522100Y416500D03*
X551500Y59597D03*
X549000Y63500D03*
Y78223D03*
X544300Y87100D03*
X549400Y81600D03*
X536500Y84500D03*
Y79000D03*
X543520Y174970D03*
X542270Y169900D03*
X539770Y174900D03*
Y169900D03*
Y172400D03*
X542270D03*
X545800Y216500D03*
X541000Y216400D03*
X537500Y232000D03*
X548300Y222600D03*
X546500Y240500D03*
X541000Y281500D03*
X539500Y292000D03*
X542000Y296450D03*
X537500Y304000D03*
X539000Y370000D03*
X539300Y365100D03*
X539000Y360000D03*
X543000Y370000D03*
X543300Y365100D03*
X543000Y360000D03*
X540600Y386300D03*
X548829Y416329D03*
X548500Y411000D03*
X538558Y413779D03*
X550369Y427558D03*
X538558D03*
X565933Y102000D03*
X562533Y102001D03*
X553000Y108500D03*
X554600Y202400D03*
X558900Y202500D03*
X566950Y220000D03*
X560000Y240000D03*
X565400Y244700D03*
X562000Y254870D03*
X554400Y267500D03*
X561700Y320300D03*
X556700D03*
X562500Y336100D03*
Y326100D03*
X562000Y331600D03*
X560000Y342100D03*
X568100Y366400D03*
Y361700D03*
X568326Y371200D03*
X563800Y390700D03*
X567500Y386500D03*
X568600Y376000D03*
Y380700D03*
X564400Y396700D03*
X567500Y403000D03*
X555000Y402000D03*
X567126Y417500D03*
X555315D03*
X562180Y413779D03*
Y427558D03*
X586500Y107000D03*
Y112500D03*
X571000Y217900D03*
X576500Y219700D03*
X569943Y223300D03*
X585000Y226500D03*
X578900Y236600D03*
X583000Y297000D03*
X580300Y390700D03*
X576900Y403100D03*
X578937Y417500D03*
X572500Y413500D03*
X584000Y421900D03*
X573991Y427558D03*
X588000Y96500D03*
X600850Y112350D03*
X592000Y127063D03*
X599500Y116500D03*
X592000Y141000D03*
Y146000D03*
Y163000D03*
Y151500D03*
Y157063D03*
Y173000D03*
Y178000D03*
Y168000D03*
X587500Y190000D03*
X594003Y187000D03*
X602500Y183000D03*
X601550Y208450D03*
X596450Y210350D03*
X601953Y218853D03*
X590650Y245680D03*
X604000Y254500D03*
X591000Y271500D03*
Y278500D03*
Y291500D03*
X602500Y404000D03*
X591000D03*
X604000Y398000D03*
X597500Y421900D03*
X602559Y417500D03*
X590748Y418725D03*
X597613Y413779D03*
Y427558D03*
X606902Y186000D03*
X610500Y190500D03*
X614100Y236400D03*
X618650Y249300D03*
X609500Y254500D03*
X614500Y398000D03*
Y403500D03*
X614370Y417500D03*
X609424Y413779D03*
Y427558D03*
X633500Y108000D03*
Y102000D03*
Y96500D03*
X637900Y116900D03*
X622000Y127063D03*
Y141500D03*
Y146500D03*
Y162000D03*
Y151600D03*
Y157000D03*
Y181500D03*
Y175500D03*
X622035Y167063D03*
X628500Y189500D03*
X627500Y205374D03*
X633000Y286500D03*
X647000Y108000D03*
G54D20*
X46000Y82000D03*
X51765Y96600D03*
X79500Y234500D03*
X79600Y248900D03*
X77964Y260100D03*
X75800Y274300D03*
X72000Y271400D03*
X82500Y230500D03*
X84600Y248900D03*
X89600D03*
X82500Y273200D03*
X87100Y271300D03*
X112800Y66600D03*
X243500Y48650D03*
X252700Y44000D03*
X297700Y335100D03*
X324000Y236000D03*
X318000Y268500D03*
X324300Y254700D03*
X327500Y232000D03*
X332600Y246600D03*
X328500Y238645D03*
X327800Y246800D03*
X334350Y282000D03*
X336500Y295000D03*
X336525Y320500D03*
Y325500D03*
X341500Y338500D03*
Y328500D03*
Y333500D03*
X336525Y330500D03*
X342900Y246800D03*
X344000Y295000D03*
X358250Y340050D03*
X361124Y349876D03*
X387193Y143005D03*
X391130D03*
X387193Y150879D03*
X391130D03*
X387193Y158753D03*
X391130D03*
X387193Y166627D03*
X391130D03*
X391600Y304800D03*
X379300Y305000D03*
X383000Y328500D03*
Y333500D03*
X395067Y146942D03*
X399005D03*
X395067Y154816D03*
X399005D03*
X395067Y162690D03*
X399005D03*
X402942Y150879D03*
X406879D03*
X395067Y170564D03*
X399005D03*
X402942Y166627D03*
X406879D03*
X421360Y359970D03*
X446248Y143005D03*
Y186311D03*
X442311D03*
X441500Y297500D03*
X444000Y406500D03*
X431900Y392200D03*
X431169Y401169D03*
X444000Y411500D03*
X461996Y131193D03*
X450185Y143005D03*
X465933Y131193D03*
X473807Y135130D03*
Y139067D03*
Y146942D03*
X469870D03*
X470462Y369462D03*
X470500Y395000D03*
X493500Y359000D03*
X503000Y354600D03*
X550643Y400900D03*
X568000Y356700D03*
X555569Y388051D03*
G54D15*
X16039Y71260D03*
Y128346D03*
Y185433D03*
Y242520D03*
G54D21*
X63500Y84500D03*
X56500Y113000D03*
X54500Y171000D03*
X62000Y199500D03*
X57500Y226500D03*
X63600Y291500D03*
X75500Y62000D03*
X64400Y70000D03*
X64500Y129500D03*
X64700Y251700D03*
X79500Y308500D03*
X71000Y330500D03*
X78000D03*
X73500Y357500D03*
X70300D03*
X94500Y299000D03*
X88500Y303000D03*
X95000Y291500D03*
X87500Y295500D03*
X97800Y391800D03*
X99500Y370000D03*
X110500Y382500D03*
X107300D03*
X153500Y310500D03*
X201700Y327900D03*
X229582Y48918D03*
X225000Y396000D03*
X250222Y76300D03*
X247022D03*
X264339Y35300D03*
Y38500D03*
X269907Y76300D03*
X266707D03*
X280087Y35300D03*
Y38500D03*
X285055Y76300D03*
X281855D03*
X295835Y35300D03*
Y38500D03*
Y44900D03*
Y48100D03*
X306500Y169500D03*
X314763Y85237D03*
X312500Y87500D03*
X322710Y190299D03*
X323500Y263000D03*
X324000Y301000D03*
X325910Y190299D03*
X338500Y213500D03*
X330500Y265000D03*
X337500D03*
X332000Y301500D03*
X337000Y344000D03*
X345301Y193099D03*
Y189899D03*
X358000Y261500D03*
X344500Y265000D03*
X370500Y84000D03*
X365700Y92000D03*
X362500D03*
X374600Y178200D03*
X365101Y191559D03*
Y188359D03*
X375000Y210000D03*
X365500Y279500D03*
X369000Y413500D03*
X374500Y418500D03*
X391130Y146942D03*
Y135130D03*
Y162690D03*
Y154816D03*
Y170564D03*
Y182374D03*
Y186311D03*
X385500Y196154D03*
X387193Y186311D03*
X380000Y210000D03*
X391130Y209933D03*
X387193D03*
X394000Y223500D03*
X383000Y232500D03*
X390000D03*
X395000Y382000D03*
X395067Y143005D03*
Y131193D03*
X406879Y135130D03*
X410816D03*
X406879Y139067D03*
X402942D03*
X410811Y131188D03*
X406874D03*
X399000Y135125D03*
Y131188D03*
X395067Y135130D03*
X410816Y143005D03*
Y139067D03*
X406879Y143005D03*
X395067Y158753D03*
X399005Y150879D03*
X402942Y158753D03*
X406879Y162690D03*
Y154816D03*
Y158753D03*
X410816Y170564D03*
X399005Y166627D03*
X402942Y178437D03*
X406879D03*
X395067Y182374D03*
X399005Y186311D03*
Y190248D03*
X402942D03*
X406879Y182374D03*
Y186311D03*
Y194185D03*
X395067Y186311D03*
Y190248D03*
X402942Y182374D03*
X399005Y198122D03*
X395067D03*
X410816Y182374D03*
Y190248D03*
Y198122D03*
X402942Y186311D03*
Y194185D03*
X399005D03*
X402942Y198122D03*
X410816Y194185D03*
X406879Y190248D03*
X395067Y213870D03*
X410816Y205996D03*
X399005Y202059D03*
X395067D03*
X402942Y205996D03*
X399005D03*
X406879Y202059D03*
X410816Y209933D03*
Y202059D03*
X399005Y209933D03*
X395067D03*
X406879Y205996D03*
Y209933D03*
X402942Y202059D03*
X395067Y205996D03*
X406879Y213870D03*
Y217807D03*
X408000Y327000D03*
X420500Y82000D03*
X429000Y123500D03*
X422000D03*
X418500Y117000D03*
X415000Y123500D03*
X418690Y139067D03*
X422627Y135130D03*
X418690D03*
X414753D03*
X422627Y131193D03*
X418690D03*
X426564Y146942D03*
Y143005D03*
Y131193D03*
Y139067D03*
X422627D03*
Y143005D03*
X418690D03*
X414753D03*
Y139067D03*
X418690Y146942D03*
X414753D03*
X418690Y154816D03*
Y162690D03*
X414753Y158753D03*
X422627D03*
X426564Y154816D03*
X414753Y150879D03*
X422627D03*
X418690D03*
X426564D03*
Y178437D03*
X418690Y170564D03*
X414753Y166627D03*
X426564Y170564D03*
X414753Y178437D03*
X422627Y166627D03*
Y178437D03*
X414753Y194185D03*
X426564Y198122D03*
X418690Y182374D03*
X426564Y186311D03*
Y190248D03*
X418690Y198122D03*
X422627Y194185D03*
Y186311D03*
Y182374D03*
X426564D03*
X414753Y190248D03*
X418690D03*
Y186311D03*
X414753D03*
Y182374D03*
Y198122D03*
X426564Y194185D03*
X422627Y198122D03*
X418690Y194185D03*
X422627Y209933D03*
X418690Y205996D03*
X414753D03*
Y209933D03*
X418690Y213870D03*
X414753Y202059D03*
X426564D03*
Y205996D03*
Y209933D03*
X422627Y202059D03*
Y205996D03*
X418690Y209933D03*
X425400Y229600D03*
X420500Y229500D03*
X414900Y229800D03*
X423000Y235400D03*
X416100D03*
X429000Y274000D03*
X434437Y143005D03*
X438374Y131193D03*
X446248Y146942D03*
X442311Y143005D03*
Y146942D03*
X438374Y135130D03*
X434437Y146942D03*
X438374D03*
X446248Y139067D03*
X445939Y135439D03*
X438374Y143005D03*
Y139067D03*
X434437D03*
Y135130D03*
Y131193D03*
Y158753D03*
X442311D03*
X438374Y154816D03*
X446248D03*
Y162690D03*
X434437Y150879D03*
X442311D03*
X446248D03*
X438374Y178437D03*
Y170564D03*
X442311Y166627D03*
X434437Y178437D03*
X446248Y170564D03*
X442311Y178437D03*
X446248Y182374D03*
X438374Y190248D03*
X446248D03*
X434437Y186311D03*
Y190248D03*
Y194185D03*
Y182374D03*
X438374Y198122D03*
X442311Y190248D03*
Y194185D03*
X434437Y198122D03*
X446248D03*
X438374Y182374D03*
Y186311D03*
X446248Y194185D03*
X442311Y198122D03*
X438374Y209933D03*
Y205996D03*
Y202059D03*
X442311Y209933D03*
X438374Y213870D03*
X442311Y202059D03*
X434437D03*
Y213870D03*
X442311Y205996D03*
X446248D03*
Y202059D03*
X434437Y209933D03*
X438374Y217807D03*
X434437D03*
X430000Y386500D03*
X450185Y135130D03*
X461996Y139067D03*
X454122D03*
X458059D03*
X461996Y135130D03*
X454122D03*
X457844Y135345D03*
X449876Y131502D03*
X454122Y131193D03*
X458059Y146942D03*
X461996D03*
X450185D03*
X454122D03*
X458059Y143005D03*
X461996D03*
X450185Y139067D03*
X461996Y162690D03*
X458059Y158753D03*
X454122D03*
Y162690D03*
X450185Y158753D03*
X458059Y150879D03*
Y162690D03*
X454122Y150879D03*
X461996D03*
X454122Y154816D03*
X458059D03*
X461996D03*
X450185Y150879D03*
X458059Y178437D03*
X454122Y166627D03*
X450185D03*
Y178437D03*
X454122D03*
X461996Y170564D03*
Y178437D03*
X458060Y170564D03*
X461996Y166627D03*
X450185Y182374D03*
X458059Y190248D03*
X454122Y182374D03*
X461996D03*
X458059Y194185D03*
X461996Y186311D03*
X458059Y182374D03*
X454122Y194185D03*
X450185D03*
X454122Y190248D03*
X458059Y186311D03*
X454122Y198122D03*
X458059D03*
X461996Y190248D03*
Y198122D03*
Y194185D03*
X450185Y186311D03*
Y190248D03*
X454122Y205996D03*
X461996Y209933D03*
Y205996D03*
Y213870D03*
X458059Y202059D03*
Y205996D03*
X454122Y209933D03*
X458059D03*
X450185D03*
Y213870D03*
X454122D03*
X450185Y202059D03*
X454122D03*
X450185Y205996D03*
X454122Y217807D03*
X450185D03*
X461996D03*
X458059D03*
X479500Y92500D03*
X466500Y110400D03*
X471200Y115700D03*
X481600Y125800D03*
X476800Y120700D03*
X473807Y143005D03*
X465933Y139067D03*
X469870D03*
Y131193D03*
X473807D03*
X465933Y135130D03*
Y143005D03*
X469870D03*
X473807Y154816D03*
X465933Y162690D03*
X473807Y150879D03*
X465933Y154816D03*
X469870D03*
X475000Y163000D03*
X465933Y158753D03*
Y150879D03*
X469870D03*
X465933Y166627D03*
Y170564D03*
Y178437D03*
X469870Y166627D03*
Y170564D03*
X473807D03*
Y178437D03*
X465933Y194185D03*
X473807Y186311D03*
X469870Y198122D03*
X465933Y186311D03*
X469870Y190248D03*
X473807Y182374D03*
X469870D03*
X465933D03*
X469870Y186311D03*
X473807Y190248D03*
X469870Y194185D03*
X465933Y198122D03*
X482000Y212500D03*
X465933Y209933D03*
X469870Y213870D03*
Y209933D03*
X465933Y202059D03*
Y205996D03*
X473807Y213870D03*
X469870Y205996D03*
X473807Y209933D03*
Y217807D03*
X467000Y355500D03*
X482800Y110300D03*
X483000Y133000D03*
X485000Y154000D03*
X497500Y148500D03*
X491000Y154000D03*
X491500Y148500D03*
X497000Y154000D03*
X483100Y272800D03*
X503000Y155000D03*
X503500Y149000D03*
X534500Y253600D03*
X530000Y406500D03*
X544500Y79500D03*
X541000Y96000D03*
X540600Y234600D03*
X558000Y161500D03*
X566000Y347000D03*
X560000Y401000D03*
X580000Y104800D03*
X576500Y98000D03*
X576000Y246500D03*
X571800Y396500D03*
X587000Y184000D03*
X595500Y239000D03*
X619961Y224474D03*
Y227674D03*
G54D19*
X26378Y340080D03*
X28150Y343150D03*
X29922Y340080D03*
X33466D03*
X37010D03*
X40554D03*
X42326Y343150D03*
X38782D03*
X35238D03*
X31694D03*
G54D28*
X605315Y334449D03*
Y350984D03*
Y367519D03*
G54D24*
X126067Y184043D03*
X286067Y104043D03*
G54D31*
X640952Y201181D03*
Y220867D03*
G54D26*
X255906Y309646D03*
Y412008D03*
X494094Y309646D03*
Y412008D03*
G54D11*
X6039Y61260D03*
Y81260D03*
Y118346D03*
Y138346D03*
Y175433D03*
Y195433D03*
Y232520D03*
Y252520D03*
X26039Y61260D03*
Y81260D03*
Y118346D03*
Y138346D03*
Y175433D03*
Y195433D03*
Y232520D03*
Y252520D03*
G54D30*
X651582Y197244D03*
Y224804D03*
G54D23*
X126067Y104043D03*
Y264043D03*
X253967Y93443D03*
X265967D03*
X277867D03*
X286067Y264043D03*
G54D13*
X29528Y36811D03*
Y373031D03*
X640039Y65354D03*
Y417835D03*
G54D25*
X143567Y106043D03*
X146067Y268043D03*
X268567Y112143D03*
Y255943D03*
G54D29*
X634055Y334449D03*
Y367519D03*
G54D18*
X22834Y340080D03*
X24606Y343150D03*
X44098Y340080D03*
X45870Y343150D03*
G54D27*
X588779Y334449D03*
Y350984D03*
Y367519D03*
%LPC*%
G75*
G54D10*
X8878Y21717D03*
X4878D03*
X4000Y25619D03*
Y29619D03*
Y33619D03*
Y37619D03*
Y41619D03*
Y45619D03*
Y49619D03*
Y281619D03*
Y285619D03*
Y289619D03*
Y293619D03*
Y297619D03*
Y301619D03*
Y305619D03*
Y309619D03*
Y313619D03*
Y337619D03*
Y341619D03*
Y345619D03*
Y349619D03*
Y353619D03*
Y357619D03*
Y361619D03*
Y365619D03*
Y369619D03*
Y373619D03*
Y377619D03*
Y381619D03*
Y385619D03*
Y389619D03*
Y393619D03*
Y397619D03*
Y401619D03*
Y405619D03*
Y409619D03*
Y413619D03*
Y417619D03*
Y421619D03*
Y425619D03*
Y429619D03*
X4413Y433598D03*
X8413D03*
X24878Y21717D03*
X20878D03*
X16878D03*
X12878D03*
X12413Y433598D03*
X16413D03*
X20413D03*
X24413D03*
X28413D03*
X44878Y21717D03*
X40878D03*
X36878D03*
X32878D03*
X28878D03*
X32413Y433598D03*
X36413D03*
X40413D03*
X44413D03*
X55055Y25073D03*
X52878Y21717D03*
X48878D03*
X55055Y41073D03*
Y37073D03*
Y33073D03*
Y29073D03*
X61463Y54048D03*
X57859Y52313D03*
X55558Y49041D03*
X55055Y45073D03*
X48413Y433598D03*
X52413D03*
X56413D03*
X60413D03*
X77460Y54197D03*
X73460D03*
X69460D03*
X65460D03*
X79248Y266100D03*
X67000Y283100D03*
X76700Y357500D03*
X67100D03*
X68413Y433598D03*
X72413D03*
X76413D03*
X80413D03*
X64413D03*
X97460Y54197D03*
X93460D03*
X89460D03*
X85460D03*
X81460D03*
X86800Y230000D03*
X85600Y263700D03*
X85800Y287452D03*
X84413Y433598D03*
X88413D03*
X92413D03*
X96413D03*
X113460Y54197D03*
X109460D03*
X105460D03*
X101460D03*
X113700Y382500D03*
X104100D03*
X104413Y433598D03*
X108413D03*
X112413D03*
X100413D03*
X132920Y51926D03*
X129450Y53917D03*
X125460Y54197D03*
X121460D03*
X117460D03*
X116413Y433598D03*
X120413D03*
X124413D03*
X128413D03*
X132413D03*
X135299Y24509D03*
X150163Y21717D03*
X146163D03*
X142163D03*
X138163D03*
X135299Y28509D03*
Y32509D03*
Y36509D03*
Y40509D03*
Y44509D03*
X134977Y48496D03*
X144000Y62500D03*
X138500Y75000D03*
X140413Y433598D03*
X144413D03*
X148413D03*
X136413D03*
X158163Y21717D03*
X154163D03*
X158795Y25667D03*
Y41667D03*
Y37667D03*
Y33667D03*
Y29667D03*
X160736Y49309D03*
X159112Y45654D03*
X163543Y52159D03*
X151840Y79935D03*
X167100Y405600D03*
X152413Y433598D03*
X156413D03*
X160413D03*
X164413D03*
X180341Y47225D03*
X178196Y50601D03*
X168413Y433598D03*
X172413D03*
X176413D03*
X180413D03*
X184413D03*
X191535Y28900D03*
X201950Y29050D03*
X200413Y433598D03*
X188413D03*
X192413D03*
X196413D03*
X208300Y289500D03*
X217300D03*
X209660Y331500D03*
X204413Y433598D03*
X208413D03*
X212413D03*
X216413D03*
X220413D03*
X232700Y29100D03*
X221800Y289500D03*
X224413Y433598D03*
X228413D03*
X232413D03*
X236413D03*
X254527Y28900D03*
X244619D03*
X240508Y76300D03*
Y66700D03*
X243822Y76300D03*
X253422D03*
X240413Y433598D03*
X244413D03*
X248413D03*
X252413D03*
X264339Y32100D03*
X264304Y28900D03*
X272309D03*
X264339Y41700D03*
X263507Y76300D03*
X256413Y433598D03*
X260413D03*
X264413D03*
X268413D03*
X272413D03*
X280087Y41700D03*
Y32100D03*
X280052Y28900D03*
X288057D03*
X288255Y76300D03*
X273107D03*
X278655D03*
X284500Y181100D03*
X277000Y198700D03*
X286600D03*
X284500Y190700D03*
X286151Y329500D03*
X288413Y433598D03*
X284413D03*
X280413D03*
X276413D03*
X295835Y41700D03*
Y32100D03*
X295800Y28900D03*
X298726Y43529D03*
Y49471D03*
X304413Y433598D03*
X300413D03*
X296413D03*
X292413D03*
X307708Y28900D03*
X321402Y54197D03*
X317402D03*
X310237Y89763D03*
X317025Y82975D03*
X319510Y190299D03*
X322200Y325000D03*
X310600Y330500D03*
X324413Y433598D03*
X320413D03*
X316413D03*
X312413D03*
X308413D03*
X329402Y54197D03*
X325402D03*
X337402D03*
X341402D03*
X333402D03*
X338599Y108500D03*
X337500Y113000D03*
Y122600D03*
X329110Y190299D03*
X340413Y433598D03*
X336413D03*
X332413D03*
X328413D03*
X345402Y54197D03*
X349402D03*
X353402D03*
X357402D03*
X359300Y92000D03*
X348199Y108500D03*
X348264Y104707D03*
X357864D03*
X345301Y196299D03*
Y186699D03*
X354850Y276100D03*
X354800Y289800D03*
X355000Y332500D03*
X356413Y433598D03*
X352413D03*
X348413D03*
X344413D03*
X369402Y54197D03*
X373402D03*
X377402D03*
X361402D03*
X365402D03*
X373500Y78000D03*
X368900Y92000D03*
X373500Y94000D03*
X365101Y194759D03*
Y185159D03*
X376413Y433598D03*
X372413D03*
X368413D03*
X364413D03*
X360413D03*
X381402Y54197D03*
X385402D03*
X389402D03*
X393402D03*
X379500Y72500D03*
X380500Y77400D03*
X390000Y100500D03*
X387193Y135130D03*
X391130Y139067D03*
X387193D03*
Y146942D03*
Y154816D03*
Y162690D03*
Y170564D03*
X391130Y178437D03*
X387193D03*
X391130Y205996D03*
X387193Y217807D03*
X392413Y433598D03*
X388413D03*
X384413D03*
X380413D03*
X397402Y54197D03*
X401402D03*
X405402D03*
X409402D03*
X396400Y100500D03*
X409200D03*
X398450Y116099D03*
X408050D03*
X395067Y139067D03*
X399005D03*
Y143005D03*
X402942D03*
Y146942D03*
X406879D03*
X410816D03*
X395067Y150879D03*
X402942Y154816D03*
X399005Y158753D03*
X410816D03*
X402942Y162690D03*
X410816D03*
Y150879D03*
Y154816D03*
X395067Y166627D03*
X410816D03*
X402942Y170564D03*
X406879D03*
X395067Y178437D03*
X399005D03*
X410816D03*
X406879Y198122D03*
X399005Y182374D03*
X410816Y186311D03*
X395067Y194185D03*
X402942Y209933D03*
X408413Y433598D03*
X404413D03*
X400413D03*
X396413D03*
X417402Y54197D03*
X421402D03*
X425402D03*
X429402D03*
X413402D03*
X413622Y75000D03*
X414753Y131193D03*
X422627Y146942D03*
X426564Y135130D03*
X414753Y162690D03*
Y154816D03*
X418690Y158753D03*
X422627Y162690D03*
Y154816D03*
X426564Y162690D03*
Y158753D03*
X418690Y166627D03*
X414753Y170564D03*
X422627D03*
X418690Y178437D03*
X426564Y166627D03*
X422627Y190248D03*
X414753Y213870D03*
X418690Y202059D03*
X426564Y217807D03*
X428413Y433598D03*
X424413D03*
X420413D03*
X416413D03*
X412413D03*
X433402Y54197D03*
X437402D03*
X441402D03*
X445402D03*
X444050Y116599D03*
X434450D03*
X442311Y139067D03*
X446248Y158753D03*
X442311Y162690D03*
X434437D03*
Y154816D03*
X438374Y162690D03*
Y150879D03*
Y158753D03*
X442311Y154816D03*
X438374Y166627D03*
X446248D03*
X434437Y170564D03*
X442311D03*
X446248Y178437D03*
X434437Y166627D03*
X442311Y182374D03*
X438374Y194185D03*
X434437Y205996D03*
X446248Y209933D03*
X446500Y289500D03*
X439500Y337892D03*
X443000Y401500D03*
Y396500D03*
X444000Y416500D03*
X444413Y433598D03*
X440413D03*
X436413D03*
X432413D03*
X449402Y54197D03*
X453402D03*
X457402D03*
X461402D03*
X450930Y122167D03*
X460530D03*
X454122Y143005D03*
X457844Y131408D03*
X450185Y154816D03*
X461996Y158753D03*
X450185Y162690D03*
X458059Y166627D03*
X450185Y170564D03*
X454123D03*
X454122Y186311D03*
X450185Y198122D03*
X461996Y202059D03*
X458059Y213870D03*
X464413Y433598D03*
X460413D03*
X456413D03*
X452413D03*
X448413D03*
X465402Y54197D03*
X469402D03*
X473402D03*
X477402D03*
X481402D03*
X465933Y146942D03*
X469870Y135130D03*
Y178437D03*
X473807Y166627D03*
X465933Y190248D03*
X473807Y205996D03*
X469870Y217807D03*
X480413Y433598D03*
X476413D03*
X472413D03*
X468413D03*
X485402Y54197D03*
X489402D03*
X493402D03*
X497402D03*
X496413Y433598D03*
X492413D03*
X488413D03*
X484413D03*
X501402Y54197D03*
X505402D03*
X509402D03*
X513402D03*
X516413Y433598D03*
X512413D03*
X508413D03*
X504413D03*
X500413D03*
X517402Y54197D03*
X521402D03*
X525402D03*
X529402D03*
X533402D03*
X532413Y433598D03*
X528413D03*
X524413D03*
X520413D03*
X537402Y54197D03*
X541402D03*
X545402D03*
X549402D03*
X548413Y433598D03*
X544413D03*
X540413D03*
X536413D03*
X553402Y54197D03*
X557402D03*
X561402D03*
X565402D03*
X566600Y212900D03*
X568413Y433598D03*
X564413D03*
X560413D03*
X556413D03*
X552413D03*
X569402Y54197D03*
X573402D03*
X577402D03*
X581402D03*
X585402D03*
X584413Y433598D03*
X580413D03*
X576413D03*
X572413D03*
X589402Y54197D03*
X593402D03*
X597402D03*
X601402D03*
X600413Y433598D03*
X596413D03*
X592413D03*
X588413D03*
X605402Y54197D03*
X609402D03*
X613402D03*
X617402D03*
X621402D03*
X619961Y230874D03*
Y221274D03*
X620413Y433598D03*
X616413D03*
X612413D03*
X608413D03*
X604413D03*
X625402Y54197D03*
X629402D03*
X636413Y433598D03*
X632413D03*
X628413D03*
X624413D03*
X649402Y54197D03*
X653402D03*
X656039Y57205D03*
Y61205D03*
Y65205D03*
Y69205D03*
Y73205D03*
Y77205D03*
Y81205D03*
Y85205D03*
Y89205D03*
Y93205D03*
Y97205D03*
Y101205D03*
Y105205D03*
Y109205D03*
Y113205D03*
Y117205D03*
Y121205D03*
Y125205D03*
Y129205D03*
Y145205D03*
Y133205D03*
Y137205D03*
Y141205D03*
Y149205D03*
Y153205D03*
Y157205D03*
Y161205D03*
Y165205D03*
Y169205D03*
Y173205D03*
Y177205D03*
Y181205D03*
Y235585D03*
Y311909D03*
Y315909D03*
Y319909D03*
Y323909D03*
Y327909D03*
Y331909D03*
Y335909D03*
Y339909D03*
Y343909D03*
Y347909D03*
Y351909D03*
Y355909D03*
Y359909D03*
Y363909D03*
Y367909D03*
Y371909D03*
Y375909D03*
Y379909D03*
Y383909D03*
Y387909D03*
Y391909D03*
Y395909D03*
Y399909D03*
Y403909D03*
Y407909D03*
Y411909D03*
Y415909D03*
Y419909D03*
Y423909D03*
Y427909D03*
Y431909D03*
X652413Y433598D03*
X648413D03*
X644413D03*
X640413D03*
G54D32*
G01X136000Y-65500D02*
Y-158000D01*
X506000D01*
Y-65500D01*
X136000D01*
G01X316000D02*
Y-158000D01*
G54D14*
X19878Y36811D03*
X22704Y29987D03*
Y43635D03*
X19878Y373031D03*
X22704Y366207D03*
Y379855D03*
X29528Y27161D03*
X36352Y29987D03*
X39178Y36811D03*
X36352Y43635D03*
X29528Y46461D03*
Y363381D03*
X36352Y366207D03*
X39178Y373031D03*
X36352Y379855D03*
X29528Y382681D03*
X633215Y58530D03*
Y72178D03*
X630389Y65354D03*
X633215Y424659D03*
X630389Y417835D03*
X633215Y411011D03*
X640039Y55704D03*
X646863Y58530D03*
X649689Y65354D03*
X646863Y72178D03*
X640039Y75004D03*
Y408185D03*
X646863Y411011D03*
X649689Y417835D03*
X646863Y424659D03*
X640039Y427485D03*
G54D33*
G01X329433Y-125500D02*
Y-133000D01*
X333167D01*
G01X340480D02*
Y-128000D01*
G01Y-128875D02*
X340107Y-128375D01*
X339547Y-128125D01*
X338893Y-128000D01*
X338240Y-128250D01*
X337680Y-128750D01*
X337307Y-129500D01*
X337120Y-130500D01*
X337307Y-131500D01*
X337680Y-132250D01*
X338240Y-132750D01*
X338893Y-133000D01*
X339547Y-132875D01*
X340107Y-132500D01*
X340480Y-132000D01*
G01X344340Y-135250D02*
X344900Y-135500D01*
X345647Y-135250D01*
X346113Y-134750D01*
X346487Y-134125D01*
X347047Y-132125D01*
X348260Y-128000D01*
G01X345273D02*
X347047Y-132125D01*
G01X352400Y-129625D02*
X355387D01*
X355107Y-128750D01*
X354640Y-128250D01*
X353987Y-128000D01*
X353333Y-128125D01*
X352773Y-128500D01*
X352400Y-129375D01*
X352213Y-130125D01*
Y-130875D01*
X352400Y-131625D01*
X352867Y-132375D01*
X353427Y-132875D01*
X354080Y-133000D01*
X354733Y-132750D01*
X355387Y-132000D01*
G01X359993Y-133000D02*
Y-128000D01*
G01Y-129000D02*
X360460Y-128500D01*
X360927Y-128125D01*
X361580Y-128000D01*
X362047Y-128125D01*
X362607Y-128500D01*
G01X368800Y-133250D02*
X368613Y-133125D01*
Y-132875D01*
X368800Y-132750D01*
X368987Y-132875D01*
Y-133125D01*
X368800Y-133250D01*
G01Y-129875D02*
X368613Y-129750D01*
Y-129500D01*
X368800Y-129375D01*
X368987Y-129500D01*
Y-129750D01*
X368800Y-129875D01*
G01X336747Y-120500D02*
Y-113000D01*
X338613D01*
X339360Y-113375D01*
X339920Y-113875D01*
X340387Y-114625D01*
X340760Y-115500D01*
X340853Y-116750D01*
X340760Y-118000D01*
X340387Y-118875D01*
X339920Y-119625D01*
X339360Y-120125D01*
X338613Y-120500D01*
X336747D01*
G01X347980D02*
Y-115500D01*
G01Y-116375D02*
X347607Y-115875D01*
X347047Y-115625D01*
X346393Y-115500D01*
X345740Y-115750D01*
X345180Y-116250D01*
X344807Y-117000D01*
X344620Y-118000D01*
X344807Y-119000D01*
X345180Y-119750D01*
X345740Y-120250D01*
X346393Y-120500D01*
X347047Y-120375D01*
X347607Y-120000D01*
X347980Y-119500D01*
G01X353800Y-113000D02*
Y-120500D01*
G01X352493Y-115500D02*
X355107D01*
G01X359900Y-117125D02*
X362887D01*
X362607Y-116250D01*
X362140Y-115750D01*
X361487Y-115500D01*
X360833Y-115625D01*
X360273Y-116000D01*
X359900Y-116875D01*
X359713Y-117625D01*
Y-118375D01*
X359900Y-119125D01*
X360367Y-119875D01*
X360927Y-120375D01*
X361580Y-120500D01*
X362233Y-120250D01*
X362887Y-119500D01*
G01X368800Y-120750D02*
X368613Y-120625D01*
Y-120375D01*
X368800Y-120250D01*
X368987Y-120375D01*
Y-120625D01*
X368800Y-120750D01*
G01Y-117375D02*
X368613Y-117250D01*
Y-117000D01*
X368800Y-116875D01*
X368987Y-117000D01*
Y-117250D01*
X368800Y-117375D01*
G01X382027Y-114250D02*
X382587Y-113500D01*
X383240Y-113125D01*
X383987Y-113000D01*
X384920Y-113250D01*
X385573Y-113875D01*
X385760Y-114625D01*
X385667Y-115375D01*
X385293Y-116000D01*
X383427Y-117250D01*
X382587Y-118125D01*
X382027Y-119375D01*
X381840Y-120500D01*
X385760D01*
G01X391300Y-113000D02*
X390553Y-113250D01*
X389993Y-113875D01*
X389620Y-114625D01*
X389340Y-115625D01*
X389247Y-116750D01*
X389340Y-117875D01*
X389620Y-118875D01*
X389993Y-119625D01*
X390553Y-120250D01*
X391300Y-120500D01*
X392047Y-120250D01*
X392607Y-119625D01*
X392980Y-118875D01*
X393260Y-117875D01*
X393353Y-116750D01*
X393260Y-115625D01*
X392980Y-114625D01*
X392607Y-113875D01*
X392047Y-113250D01*
X391300Y-113000D01*
G01X397027Y-114250D02*
X397587Y-113500D01*
X398240Y-113125D01*
X398987Y-113000D01*
X399920Y-113250D01*
X400573Y-113875D01*
X400760Y-114625D01*
X400667Y-115375D01*
X400293Y-116000D01*
X398427Y-117250D01*
X397587Y-118125D01*
X397027Y-119375D01*
X396840Y-120500D01*
X400760D01*
G01X404527Y-114250D02*
X405087Y-113500D01*
X405740Y-113125D01*
X406487Y-113000D01*
X407420Y-113250D01*
X408073Y-113875D01*
X408260Y-114625D01*
X408167Y-115375D01*
X407793Y-116000D01*
X405927Y-117250D01*
X405087Y-118125D01*
X404527Y-119375D01*
X404340Y-120500D01*
X408260D01*
G01X412587Y-118000D02*
X415013D01*
G01X421300Y-113000D02*
X420553Y-113250D01*
X419993Y-113875D01*
X419620Y-114625D01*
X419340Y-115625D01*
X419247Y-116750D01*
X419340Y-117875D01*
X419620Y-118875D01*
X419993Y-119625D01*
X420553Y-120250D01*
X421300Y-120500D01*
X422047Y-120250D01*
X422607Y-119625D01*
X422980Y-118875D01*
X423260Y-117875D01*
X423353Y-116750D01*
X423260Y-115625D01*
X422980Y-114625D01*
X422607Y-113875D01*
X422047Y-113250D01*
X421300Y-113000D01*
G01X427027Y-114250D02*
X427587Y-113500D01*
X428240Y-113125D01*
X428987Y-113000D01*
X429920Y-113250D01*
X430573Y-113875D01*
X430760Y-114625D01*
X430667Y-115375D01*
X430293Y-116000D01*
X428427Y-117250D01*
X427587Y-118125D01*
X427027Y-119375D01*
X426840Y-120500D01*
X430760D01*
G01X435087Y-118000D02*
X437513D01*
G01X442027Y-114250D02*
X442587Y-113500D01*
X443240Y-113125D01*
X443987Y-113000D01*
X444920Y-113250D01*
X445573Y-113875D01*
X445760Y-114625D01*
X445667Y-115375D01*
X445293Y-116000D01*
X443427Y-117250D01*
X442587Y-118125D01*
X442027Y-119375D01*
X441840Y-120500D01*
X445760D01*
G01X449247Y-119375D02*
X449807Y-120000D01*
X450460Y-120375D01*
X451300Y-120500D01*
X452140Y-120250D01*
X452793Y-119750D01*
X453260Y-118875D01*
X453353Y-117875D01*
X453167Y-116875D01*
X452700Y-116250D01*
X452047Y-115750D01*
X451393Y-115625D01*
X450740Y-115750D01*
X449900Y-116250D01*
X450180Y-113000D01*
X452700D01*
G01X336933Y-108000D02*
Y-100500D01*
X339267D01*
X340013Y-100875D01*
X340480Y-101375D01*
X340667Y-102375D01*
X340480Y-103375D01*
X339920Y-104000D01*
X339267Y-104375D01*
X336933D01*
G01X339267D02*
X340667Y-108000D01*
G01X344900Y-104625D02*
X347887D01*
X347607Y-103750D01*
X347140Y-103250D01*
X346487Y-103000D01*
X345833Y-103125D01*
X345273Y-103500D01*
X344900Y-104375D01*
X344713Y-105125D01*
Y-105875D01*
X344900Y-106625D01*
X345367Y-107375D01*
X345927Y-107875D01*
X346580Y-108000D01*
X347233Y-107750D01*
X347887Y-107000D01*
G01X352120Y-103000D02*
X353800Y-108000D01*
X355480Y-103000D01*
G01X368800Y-108250D02*
X368613Y-108125D01*
Y-107875D01*
X368800Y-107750D01*
X368987Y-107875D01*
Y-108125D01*
X368800Y-108250D01*
G01Y-104875D02*
X368613Y-104750D01*
Y-104500D01*
X368800Y-104375D01*
X368987Y-104500D01*
Y-104750D01*
X368800Y-104875D01*
G01X383800Y-100500D02*
X383053Y-100750D01*
X382493Y-101375D01*
X382120Y-102125D01*
X381840Y-103125D01*
X381747Y-104250D01*
X381840Y-105375D01*
X382120Y-106375D01*
X382493Y-107125D01*
X383053Y-107750D01*
X383800Y-108000D01*
X384547Y-107750D01*
X385107Y-107125D01*
X385480Y-106375D01*
X385760Y-105375D01*
X385853Y-104250D01*
X385760Y-103125D01*
X385480Y-102125D01*
X385107Y-101375D01*
X384547Y-100750D01*
X383800Y-100500D01*
G01X391300Y-108000D02*
Y-100500D01*
X390180Y-102000D01*
G01Y-108000D02*
X392420D01*
G01X336933Y-95500D02*
Y-88000D01*
X339173D01*
X339920Y-88375D01*
X340480Y-89250D01*
X340667Y-90250D01*
X340480Y-91250D01*
X340013Y-92000D01*
X339173Y-92375D01*
X336933D01*
G01X344620Y-95750D02*
X347980Y-88000D01*
G01X351653Y-95500D02*
Y-88000D01*
X355947Y-95500D01*
Y-88000D01*
G01X368800Y-95750D02*
X368613Y-95625D01*
Y-95375D01*
X368800Y-95250D01*
X368987Y-95375D01*
Y-95625D01*
X368800Y-95750D01*
G01Y-92375D02*
X368613Y-92250D01*
Y-92000D01*
X368800Y-91875D01*
X368987Y-92000D01*
Y-92250D01*
X368800Y-92375D01*
G01X381933Y-95500D02*
Y-88000D01*
X384267D01*
X385013Y-88375D01*
X385480Y-88875D01*
X385667Y-89875D01*
X385480Y-90875D01*
X384920Y-91500D01*
X384267Y-91875D01*
X381933D01*
G01X384267D02*
X385667Y-95500D01*
G01X392420D02*
Y-88000D01*
X388967Y-93375D01*
X393633D01*
G01X398800Y-88000D02*
X398053Y-88250D01*
X397493Y-88875D01*
X397120Y-89625D01*
X396840Y-90625D01*
X396747Y-91750D01*
X396840Y-92875D01*
X397120Y-93875D01*
X397493Y-94625D01*
X398053Y-95250D01*
X398800Y-95500D01*
X399547Y-95250D01*
X400107Y-94625D01*
X400480Y-93875D01*
X400760Y-92875D01*
X400853Y-91750D01*
X400760Y-90625D01*
X400480Y-89625D01*
X400107Y-88875D01*
X399547Y-88250D01*
X398800Y-88000D01*
G01X406300D02*
X405553Y-88250D01*
X404993Y-88875D01*
X404620Y-89625D01*
X404340Y-90625D01*
X404247Y-91750D01*
X404340Y-92875D01*
X404620Y-93875D01*
X404993Y-94625D01*
X405553Y-95250D01*
X406300Y-95500D01*
X407047Y-95250D01*
X407607Y-94625D01*
X407980Y-93875D01*
X408260Y-92875D01*
X408353Y-91750D01*
X408260Y-90625D01*
X407980Y-89625D01*
X407607Y-88875D01*
X407047Y-88250D01*
X406300Y-88000D01*
G01X412027Y-92375D02*
X412680Y-91500D01*
X413240Y-91000D01*
X413987Y-90750D01*
X414640Y-91000D01*
X415107Y-91500D01*
X415480Y-92250D01*
X415573Y-93125D01*
X415480Y-93875D01*
X415107Y-94625D01*
X414547Y-95250D01*
X413893Y-95500D01*
X413147Y-95250D01*
X412493Y-94500D01*
X412120Y-93375D01*
X412027Y-92125D01*
X412213Y-90500D01*
X412493Y-89625D01*
X412960Y-88750D01*
X413613Y-88125D01*
X414267Y-88000D01*
X414920Y-88250D01*
X415387Y-88875D01*
G01X420087Y-93000D02*
X422513D01*
G01X429547Y-91500D02*
X429920Y-91125D01*
X430200Y-90500D01*
X430387Y-89625D01*
X430200Y-88875D01*
X429827Y-88375D01*
X429173Y-88000D01*
X426653D01*
Y-95500D01*
X429733D01*
X430387Y-95000D01*
X430760Y-94250D01*
X430947Y-93375D01*
X430760Y-92500D01*
X430200Y-91750D01*
X429547Y-91500D01*
X426653D01*
G01X436300Y-88000D02*
X435553Y-88250D01*
X434993Y-88875D01*
X434620Y-89625D01*
X434340Y-90625D01*
X434247Y-91750D01*
X434340Y-92875D01*
X434620Y-93875D01*
X434993Y-94625D01*
X435553Y-95250D01*
X436300Y-95500D01*
X437047Y-95250D01*
X437607Y-94625D01*
X437980Y-93875D01*
X438260Y-92875D01*
X438353Y-91750D01*
X438260Y-90625D01*
X437980Y-89625D01*
X437607Y-88875D01*
X437047Y-88250D01*
X436300Y-88000D01*
G01X443800D02*
X443053Y-88250D01*
X442493Y-88875D01*
X442120Y-89625D01*
X441840Y-90625D01*
X441747Y-91750D01*
X441840Y-92875D01*
X442120Y-93875D01*
X442493Y-94625D01*
X443053Y-95250D01*
X443800Y-95500D01*
X444547Y-95250D01*
X445107Y-94625D01*
X445480Y-93875D01*
X445760Y-92875D01*
X445853Y-91750D01*
X445760Y-90625D01*
X445480Y-89625D01*
X445107Y-88875D01*
X444547Y-88250D01*
X443800Y-88000D01*
G01X451300D02*
X450553Y-88250D01*
X449993Y-88875D01*
X449620Y-89625D01*
X449340Y-90625D01*
X449247Y-91750D01*
X449340Y-92875D01*
X449620Y-93875D01*
X449993Y-94625D01*
X450553Y-95250D01*
X451300Y-95500D01*
X452047Y-95250D01*
X452607Y-94625D01*
X452980Y-93875D01*
X453260Y-92875D01*
X453353Y-91750D01*
X453260Y-90625D01*
X452980Y-89625D01*
X452607Y-88875D01*
X452047Y-88250D01*
X451300Y-88000D01*
G01X458800Y-95500D02*
Y-88000D01*
X457680Y-89500D01*
G01Y-95500D02*
X459920D01*
G01X465087Y-93000D02*
X467513D01*
G01X473800Y-88000D02*
X473053Y-88250D01*
X472493Y-88875D01*
X472120Y-89625D01*
X471840Y-90625D01*
X471747Y-91750D01*
X471840Y-92875D01*
X472120Y-93875D01*
X472493Y-94625D01*
X473053Y-95250D01*
X473800Y-95500D01*
X474547Y-95250D01*
X475107Y-94625D01*
X475480Y-93875D01*
X475760Y-92875D01*
X475853Y-91750D01*
X475760Y-90625D01*
X475480Y-89625D01*
X475107Y-88875D01*
X474547Y-88250D01*
X473800Y-88000D01*
G01X479527Y-89250D02*
X480087Y-88500D01*
X480740Y-88125D01*
X481487Y-88000D01*
X482420Y-88250D01*
X483073Y-88875D01*
X483260Y-89625D01*
X483167Y-90375D01*
X482793Y-91000D01*
X480927Y-92250D01*
X480087Y-93125D01*
X479527Y-94375D01*
X479340Y-95500D01*
X483260D01*
G54D34*
G01X145964Y-110118D02*
G03I-634J0D01*
G01X149695D02*
G03I-1038J0D01*
G01X168013Y-137456D02*
G03I-634J0D01*
G01X155900Y-133655D02*
G03I-632J0D01*
G01X161735Y-128639D02*
G03I-1458J0D01*
G01X158530Y-131428D02*
G03I-1041J0D01*
G01X158461Y-119126D02*
G03I-1283J0D01*
G01X162690Y-117490D02*
G03I-1584J0D01*
G01X169809Y-121292D02*
G03I-2180J0D01*
G01X165531Y-125255D02*
G03I-1869J0D01*
G01X167813Y-115513D02*
G03I-1971J0D01*
G01X154775Y-120500D02*
G03I-892J0D01*
G01X162681Y-102774D02*
G03I-1584J0D01*
G01X158451Y-101149D02*
G03I-1283J0D01*
G01X159258Y-110118D02*
G03I-1868J0D01*
G01X169812Y-98951D02*
G03I-2180J0D01*
G01X167802Y-104739D02*
G03I-1971J0D01*
G01X165183Y-110118D02*
G03I-2180J0D01*
G01X171881D02*
G03I-2642J0D01*
G01X152135Y-98681D02*
G03I-632J0D01*
G01X154064Y-110118D02*
G03I-1460J0D01*
G01X154764Y-99775D02*
G03I-892J0D01*
G01X158530Y-88809D02*
G03I-1041J0D01*
G01X161742Y-91601D02*
G03I-1458J0D01*
G01X165531Y-94981D02*
G03I-1869J0D01*
G01X171080Y-131739D02*
G03I-1282J0D01*
G01X169322Y-135033D02*
G03I-892J0D01*
G01X180669Y-131528D02*
G03I-1870J0D01*
G01X180255Y-136311D02*
G03I-1456J0D01*
G01X179841Y-140261D02*
G03I-1042J0D01*
G01X179433Y-143587D02*
G03I-634J0D01*
G01X181439Y-119680D02*
G03I-2640J0D01*
G01X175373Y-123081D02*
G03I-1968J0D01*
G01X173018Y-127816D02*
G03I-1584J0D01*
G01X174681Y-116876D02*
G03I-2640J0D01*
G01X180979Y-125917D02*
G03I-2180J0D01*
G01X186177Y-123075D02*
G03I-1971J0D01*
G01X188199Y-116876D02*
G03I-2640J0D01*
G01X175452Y-97124D02*
G03I-1968J0D01*
G01X186225Y-97178D02*
G03I-1971J0D01*
G01X181439Y-100556D02*
G03I-2640J0D01*
G01X174681Y-103361D02*
G03I-2640J0D01*
G01X188199D02*
G03I-2640J0D01*
G01X179841Y-79975D02*
G03I-1042J0D01*
G01X171217Y-88444D02*
G03I-1282J0D01*
G01X173123Y-92378D02*
G03I-1584J0D01*
G01X180255Y-83924D02*
G03I-1456J0D01*
G01X180669Y-88708D02*
G03I-1870J0D01*
G01X180979Y-94320D02*
G03I-2180J0D01*
G01X179433Y-76648D02*
G03I-634J0D01*
G01X191096Y-134658D02*
G03I-892J0D01*
G01X192135Y-136781D02*
G03I-631J0D01*
G01X198775Y-128635D02*
G03I-1458J0D01*
G01X195808Y-125255D02*
G03I-1869J0D01*
G01X200547Y-113952D02*
G03X203345Y-117196I7247J3422D01*
G01X192148Y-121285D02*
G03I-2180J0D01*
G01X187928Y-127802D02*
G03I-1584J0D01*
G01X189667Y-131511D02*
G03I-1283J0D01*
G01X200699Y-105836D02*
G03X200547Y-113953I8974J-4228D01*
G01X208284Y-101612D02*
G03X200698Y-105835I-219J-8531D01*
G01X192148Y-98951D02*
G03I-2180J0D01*
G01X191108Y-82727D02*
G03I-634J0D01*
G01X190184Y-85250D02*
G03I-893J0D01*
G01X195808Y-94981D02*
G03I-1869J0D01*
G01X187839Y-92457D02*
G03I-1584J0D01*
G01X189190Y-88538D02*
G03I-1283J0D01*
G01X214259Y-115661D02*
G03X213314Y-114453I-714J415D01*
G01X202049Y-108260D02*
G03X205722Y-116181I7039J-1548D01*
G01X218075Y-112869D02*
G03X219083Y-115752I4343J-99D01*
G01X208854Y-116658D02*
G03X213313Y-114452I-2485J10632D01*
G01X208470Y-118462D02*
G03X214261Y-115663I-1122J9711D01*
G01X203346Y-117195D02*
G03X208470Y-118461I4545J7394D01*
G01X205721Y-116179D02*
G03X208853Y-116659I2561J6250D01*
G01X215903Y-114020D02*
G03X219079Y-118061I6190J1597D01*
G01X215904Y-114020D02*
Y-111835D01*
G01X227413Y-112869D02*
X218074D01*
G01X214175Y-103951D02*
G03X208283Y-101613I-6403J-7542D01*
G01X213150Y-105147D02*
G03X214175Y-103951I410J686D01*
G01X213152Y-105146D02*
G03X208030Y-103430I-5122J-6786D01*
G01X208029Y-103429D02*
G03X202049Y-108259I-48J-6058D01*
G01X225189Y-111399D02*
G03X218071I-3559J159D01*
G01X218070Y-111418D02*
Y-111399D01*
G01X225188Y-111418D02*
X218070D01*
G01X227412Y-111835D02*
G03X215906I-5753J223D01*
G01X230059Y-117625D02*
Y-102034D01*
G01X230060Y-117626D02*
G03X232080I1010J239D01*
G01X226590Y-116472D02*
G03X225311Y-115210I-817J451D01*
G01X234673Y-114020D02*
G03X237849Y-118061I6190J1597D01*
G01X232081Y-102041D02*
Y-117625D01*
G01X219083Y-115753D02*
G03X225311Y-115211I2844J3371D01*
G01X219079Y-118060D02*
G03X226591Y-116473I2662J5972D01*
G01X227413Y-111835D02*
Y-112869D01*
G01X232080Y-102041D02*
G03X230060Y-102034I-1011J-236D01*
G01X225188Y-111399D02*
Y-111418D01*
G01X234675Y-114020D02*
Y-111835D01*
G01X246181D02*
G03X234675I-5753J223D01*
G01X252849Y-116771D02*
G03X254892Y-115895I-74J2994D01*
G01X236844Y-112869D02*
G03X237852Y-115752I4343J-99D01*
G01X237848Y-118060D02*
G03X245360Y-116473I2662J5972D01*
G01X245358Y-116472D02*
G03X244079Y-115210I-817J451D01*
G01X237852Y-115753D02*
G03X244080Y-115211I2844J3371D01*
G01X249566Y-115529D02*
G03X252307Y-116760I2985J2980D01*
G01Y-116761D02*
G03X252849Y-116772I366J4691D01*
G01X250282Y-118087D02*
G03X254318Y-118340I2605J9244D01*
G01X247897Y-116444D02*
G03X250283Y-118086I3752J2898D01*
G01X249568Y-115529D02*
G03X247898Y-116443I-748J-616D01*
G01X255608Y-108618D02*
G03X253612Y-107689I-3116J-4086D01*
G01X246181Y-111835D02*
Y-112869D01*
G01D02*
X236844D01*
G01X255002Y-114328D02*
G03X252723Y-112986I-3540J-3405D01*
G01X249955Y-112030D02*
G03X252723Y-112985I8208J19302D01*
G01X243957Y-111399D02*
Y-111418D01*
G01X243958Y-111399D02*
G03X236840I-3559J159D01*
G01X236841Y-111418D02*
Y-111399D01*
G01X243957Y-111418D02*
X236841D01*
G01X248537Y-109748D02*
G03X249956Y-112031I2652J66D01*
G01X248537Y-108250D02*
Y-109748D01*
G01X250179Y-106359D02*
G03X248537Y-108249I2747J-4045D01*
G01X256884Y-107368D02*
G03X250178Y-106359I-4153J-4811D01*
G01X253611Y-107689D02*
G03X251080Y-107949I-869J-3992D01*
G01X251081Y-107948D02*
G03X250837Y-110104I805J-1183D01*
G01Y-110106D02*
G03X254306Y-111513I5270J8013D01*
G01X260954Y-116041D02*
Y-107954D01*
G01X254892Y-115895D02*
G03X255001Y-114328I-764J840D01*
G01X269619Y-117484D02*
Y-106797D01*
G01X269620Y-117484D02*
G03X271926I1153J198D01*
G01X266864Y-117375D02*
G03X266002Y-116329I-764J249D01*
G01X262978Y-115462D02*
G03X266002Y-116329I2046J1428D01*
G01X260955Y-116043D02*
G03X264164Y-118351I2956J725D01*
G01X265463Y-118350D02*
X264165D01*
G01X265464Y-118352D02*
G03X266864Y-117374I-24J1525D01*
G01X256906Y-116470D02*
G03X257054Y-113728I-3143J1545D01*
G01X254317Y-118340D02*
G03X256906Y-116470I-1259J4470D01*
G01X262978Y-107954D02*
Y-115463D01*
G01X257054Y-113729D02*
G03X254307Y-111513I-3470J-1490D01*
G01X271969Y-102342D02*
G03I-1194J0D01*
G01X271926Y-106797D02*
G03X269620I-1153J-409D01*
G01X266003Y-107954D02*
X262978D01*
G01X266004Y-107955D02*
G03X266008Y-105932I-177J1012D01*
G01X262978D02*
X266008D01*
G01X262971Y-103419D02*
X262978Y-105932D01*
G01X262972Y-103418D02*
G03X260954Y-103491I-1005J-141D01*
G01Y-105932D02*
Y-103492D01*
G01X259930Y-105932D02*
X260954D01*
G01X259930D02*
G03X259981Y-107955I298J-1005D01*
G01X260954Y-107954D02*
X259982D01*
G01X255606Y-108620D02*
G03X256885Y-107367I599J667D01*
G01X290671Y-110842D02*
G03X290703Y-118351I860J-3751D01*
G01X276837Y-114305D02*
G03X278891Y-116297I4069J2141D01*
G01X274529Y-113568D02*
G03X275888Y-116443I5718J944D01*
G01X275887D02*
G03X279572Y-118352I4392J3967D01*
G01X281425Y-118350D02*
X279571D01*
G01X281425D02*
G03X284525Y-117161I0J4636D01*
G01X285201Y-116508D02*
X284524Y-117161D01*
G01X285201Y-116508D02*
G03X283966Y-115211I-695J574D01*
G01X281510Y-116675D02*
G03X283966Y-115212I-989J4453D01*
G01X278889Y-116297D02*
G03X281508Y-116677I1946J4197D01*
G01X271926Y-106797D02*
Y-117484D01*
G01X274529Y-113566D02*
Y-111839D01*
G01X276446Y-112943D02*
G03X276837Y-114305I4162J458D01*
G01X276445Y-112066D02*
Y-112943D01*
G01X283833Y-109274D02*
G03X285403Y-108106I585J852D01*
G01X285402D02*
G03X280919Y-105777I-4776J-3714D01*
G01X279541D02*
X280919D01*
G01X279540D02*
G03X274999Y-109274I1260J-6333D01*
G01X274998D02*
G03X274529Y-111839I9988J-3152D01*
G01X276849Y-109932D02*
G03X276446Y-112066I5467J-2137D01*
G01X280036Y-107542D02*
G03X276849Y-109933I664J-4205D01*
G01X282662Y-108199D02*
G03X280037Y-107539I-2313J-3650D01*
G01X283833Y-109275D02*
G03X282662Y-108202I-9277J-8949D01*
G01X294457Y-116619D02*
G03Y-112289I-51J2165D01*
G01X291853Y-116620D02*
X294456D01*
G01X291853Y-112289D02*
G03Y-116619I195J-2165D01*
G01X294165Y-118350D02*
X290701D01*
G01X294165D02*
G03X296471Y-117226I-1088J5161D01*
G01X296473Y-117625D02*
Y-117226D01*
G01X296474Y-117627D02*
G03X298494I1010J185D01*
G01X298495Y-109394D02*
Y-117625D01*
G01X301067Y-108534D02*
Y-106508D01*
G01X301615Y-108534D02*
X301067D01*
G01X301615Y-106508D02*
Y-108534D01*
G01X302461Y-106508D02*
X301615D01*
G01X302461Y-106001D02*
Y-106508D01*
G01X300223Y-106001D02*
X302461D01*
G01X300223Y-106508D02*
Y-106001D01*
G01X301067Y-106508D02*
X300223D01*
G01X305164Y-106001D02*
X304731D01*
G01X305713Y-108544D02*
X305164Y-106001D01*
G01X305171Y-108544D02*
X305713D01*
G01X304889Y-106871D02*
X305171Y-108544D01*
G01X304309D02*
X304889Y-106871D01*
G01X304086Y-108544D02*
X304309D01*
G01X303501Y-106887D02*
X304086Y-108544D01*
G01X303226D02*
X303501Y-106887D01*
G01X302698Y-108544D02*
X303226D01*
G01X303243Y-106001D02*
X302698Y-108544D01*
G01X303648Y-106001D02*
X303243D01*
G01X304192Y-107632D02*
X303648Y-106001D01*
G01X304731D02*
X304192Y-107632D01*
G01X294456Y-112288D02*
X291853D01*
G01X296473Y-110841D02*
Y-109686D01*
G01X296472Y-110841D02*
G03X292878Y-110536I-3256J-17043D01*
G01X292879Y-110535D02*
G03X290670Y-110842I280J-10112D01*
G01X298496Y-109394D02*
G03X295031Y-105933I-3962J-501D01*
G01X291563Y-105932D02*
X295031D01*
G01X291562D02*
G03X289112Y-107085I584J-4421D01*
G01Y-107086D02*
G03X289820Y-108520I585J-603D01*
G01X290987Y-107954D02*
G03X289821Y-108520I1446J-4464D01*
G01X294740Y-107954D02*
X290987D01*
G01X296473Y-109686D02*
G03X294742Y-107955I-1598J133D01*
G01X381000Y-125000D02*
Y-133000D01*
X385000D01*
G01X391000Y-125000D02*
X390200Y-125267D01*
X389600Y-125933D01*
X389200Y-126733D01*
X388900Y-127800D01*
X388800Y-129000D01*
X388900Y-130200D01*
X389200Y-131267D01*
X389600Y-132067D01*
X390200Y-132733D01*
X391000Y-133000D01*
X391800Y-132733D01*
X392400Y-132067D01*
X392800Y-131267D01*
X393100Y-130200D01*
X393200Y-129000D01*
X393100Y-127800D01*
X392800Y-126733D01*
X392400Y-125933D01*
X391800Y-125267D01*
X391000Y-125000D01*
G01X400200Y-133000D02*
Y-125000D01*
X396500Y-130733D01*
X401500D01*
G01X404000Y-135667D02*
X410000D01*
G01X415600Y-129000D02*
X417600D01*
Y-131400D01*
X417000Y-132200D01*
X416300Y-132733D01*
X415300Y-133000D01*
X414300Y-132733D01*
X413600Y-132200D01*
X413000Y-131400D01*
X412600Y-130467D01*
X412400Y-129400D01*
Y-128467D01*
X412600Y-127667D01*
X413000Y-126733D01*
X413600Y-125933D01*
X414200Y-125400D01*
X415000Y-125000D01*
X415700D01*
X416500Y-125267D01*
X417100Y-125800D01*
G01X420700Y-133000D02*
Y-125000D01*
X425300Y-133000D01*
Y-125000D01*
G01X428800Y-133000D02*
Y-125000D01*
X430800D01*
X431600Y-125400D01*
X432200Y-125933D01*
X432700Y-126733D01*
X433100Y-127667D01*
X433200Y-129000D01*
X433100Y-130333D01*
X432700Y-131267D01*
X432200Y-132067D01*
X431600Y-132600D01*
X430800Y-133000D01*
X428800D01*
G01X437100Y-126333D02*
X437700Y-125533D01*
X438400Y-125133D01*
X439200Y-125000D01*
X440200Y-125267D01*
X440900Y-125933D01*
X441100Y-126733D01*
X441000Y-127534D01*
X440600Y-128200D01*
X438600Y-129533D01*
X437700Y-130467D01*
X437100Y-131800D01*
X436900Y-133000D01*
X441100D01*
G54D16*
X17500Y91000D03*
X17000Y204500D03*
X19900Y283000D03*
X16000Y302500D03*
Y307500D03*
X45500Y126000D03*
Y161000D03*
X42000Y236800D03*
X51772Y73600D03*
X47600Y68900D03*
X47000Y100000D03*
X61400Y104900D03*
X51772Y130500D03*
X53900Y157000D03*
X60600Y161200D03*
X51772Y187987D03*
X57500Y218500D03*
X51772Y245074D03*
X48500Y271500D03*
X57500Y289000D03*
X61489Y332329D03*
X63500Y359600D03*
X67700Y65000D03*
X66400Y77400D03*
X66000Y91100D03*
X69500Y100000D03*
X74593Y202207D03*
X71400Y221700D03*
X67500Y222900D03*
X71500Y247800D03*
X80148Y253648D03*
X72000Y335000D03*
X66000Y419000D03*
X88900Y67000D03*
X83300Y87100D03*
X94500Y105000D03*
X86600Y141300D03*
X85750Y202750D03*
X93032Y246477D03*
X87200Y258300D03*
X98700Y268300D03*
X95593Y333347D03*
X94000Y420000D03*
X83000Y417000D03*
X103800Y76240D03*
X98800Y272400D03*
X104500Y305500D03*
X99000Y350000D03*
X103000Y364000D03*
X106500D03*
X110000D03*
X115500Y389000D03*
X102500Y420000D03*
X119500Y57694D03*
X127500Y290500D03*
X125095Y306095D03*
X123500Y347500D03*
X120000Y364500D03*
X129000Y365000D03*
Y370500D03*
X120000Y368000D03*
Y371500D03*
X132000Y379000D03*
X118500D03*
X132000Y375500D03*
X127000Y397061D03*
X117000Y397000D03*
X121169Y396892D03*
X150860Y67400D03*
X145000Y296500D03*
X141000Y298500D03*
X142130Y325630D03*
X140900Y355400D03*
X142000Y350000D03*
X148000Y370000D03*
X140123Y391604D03*
X135500Y383000D03*
Y390500D03*
X140100Y395600D03*
X135500Y396000D03*
X165000Y294000D03*
X166150Y304050D03*
X166700Y338800D03*
X151000Y324200D03*
X159100Y350400D03*
X151500Y370000D03*
X168500Y294000D03*
X169850Y298950D03*
X178600Y378600D03*
Y374600D03*
X175100Y382600D03*
Y387100D03*
X174600Y401600D03*
Y406100D03*
Y410600D03*
X176000Y416000D03*
X192160Y77840D03*
X190000Y301500D03*
Y305500D03*
X189500Y319000D03*
X189000Y326000D03*
X191500Y413000D03*
X215000Y69000D03*
X220000D03*
X218000Y381100D03*
X217600Y415100D03*
X228500Y382500D03*
X221500Y378500D03*
X226000D03*
X221500Y415000D03*
X225600Y415100D03*
X229500Y415000D03*
X254000Y213500D03*
X241441Y215000D03*
X241900Y238800D03*
X272330Y54871D03*
X259500Y70100D03*
X271000Y184500D03*
X269000Y215000D03*
X259000Y223000D03*
X282200Y179121D03*
X275260Y223000D03*
X280500Y224300D03*
X288000Y293000D03*
X288500Y317000D03*
X303500Y69400D03*
X298500Y184500D03*
X292000Y294720D03*
X299500Y295500D03*
X301000Y312000D03*
X311000Y193500D03*
X312000Y217000D03*
X308967Y204000D03*
X312000Y234400D03*
X311600Y252400D03*
X314500Y276500D03*
X312000Y295500D03*
X321899Y343000D03*
X321300Y423600D03*
X324800Y415200D03*
X321300Y416700D03*
X324800Y410700D03*
X341500Y233500D03*
X340953Y237000D03*
X328500Y258900D03*
X330500Y291500D03*
X338000Y315000D03*
X326000Y374000D03*
X325300Y387200D03*
X331500Y376000D03*
X338500D03*
X342000D03*
X325300Y396200D03*
Y391700D03*
X354000Y128000D03*
X351000Y130500D03*
X353500D03*
X356000D03*
X350100Y169400D03*
X352600D03*
X357600D03*
X355100D03*
X347300Y179000D03*
X351200Y196600D03*
X350500Y229500D03*
X355000Y242500D03*
X354975Y247900D03*
X343500Y258900D03*
X349000Y303000D03*
X355500Y306500D03*
X360000Y402400D03*
X376838Y100230D03*
X367000Y126000D03*
X374300Y129000D03*
X371800D03*
X374300Y132000D03*
X371800D03*
X363600Y176600D03*
X367600Y169300D03*
X364700Y169400D03*
X369560Y213000D03*
X372060D03*
X367000D03*
X364500D03*
X367000Y232000D03*
X372500D03*
X360500Y243000D03*
X367000Y241243D03*
X369500Y267500D03*
X362300Y286100D03*
X365800D03*
X374800Y291100D03*
X370300D03*
X361500Y296100D03*
X365800Y291100D03*
X362100Y291000D03*
X363100Y418300D03*
X360311Y409880D03*
X363100Y422800D03*
X384000Y102980D03*
Y109500D03*
X379800Y177100D03*
X380000Y204500D03*
X378000Y273500D03*
X388650Y292650D03*
X378000Y293200D03*
X383000D03*
X393300Y312500D03*
X383000Y341500D03*
X384300Y368700D03*
X383900Y372600D03*
X407000Y120000D03*
X399500D03*
X399000Y221407D03*
Y225000D03*
X397800Y259300D03*
X403700D03*
X399800Y278400D03*
X409100Y281300D03*
X409300Y286300D03*
X409200Y291700D03*
X397500Y312900D03*
X407500Y305000D03*
X397300Y320700D03*
X398000Y352000D03*
X410000Y358543D03*
X409650Y403950D03*
X412350Y401250D03*
Y397150D03*
X409650Y394450D03*
X422000Y77500D03*
X413500Y88500D03*
X423000Y100500D03*
X427800Y100300D03*
X429400Y107500D03*
X417500Y352000D03*
X419150Y394450D03*
X416450Y401250D03*
Y397150D03*
X419150Y403950D03*
X434500Y77000D03*
X441400Y78100D03*
X433500Y100500D03*
X444200D03*
X431000Y116500D03*
X444000Y226000D03*
Y250000D03*
X439500Y266500D03*
X444000Y263000D03*
X447200Y347500D03*
X446000Y374500D03*
X431000Y416000D03*
X448430Y89540D03*
X463500Y86500D03*
X450000Y108200D03*
X454600Y108500D03*
X462000Y224500D03*
Y250000D03*
X460000Y284500D03*
Y289500D03*
X459500Y322000D03*
X459000Y326000D03*
X454000Y393500D03*
Y397000D03*
X450000Y407000D03*
X481000Y70700D03*
X479867Y138867D03*
X481500Y182016D03*
X478000Y198000D03*
X471000Y259200D03*
X477500Y259000D03*
X471000Y347000D03*
X471400Y363300D03*
X489400Y126300D03*
X493300Y121500D03*
X496000Y167500D03*
Y179258D03*
X496500Y192500D03*
X496000Y205500D03*
X492500Y272200D03*
X491800Y277700D03*
X503950Y143000D03*
X512100Y249500D03*
X507100Y240700D03*
X512100D03*
Y244700D03*
Y262500D03*
X512300Y254400D03*
X512200Y258700D03*
X512650Y268150D03*
X511900Y276200D03*
X508950Y273250D03*
X506100Y280600D03*
X505000Y379500D03*
X504500Y376000D03*
X533000Y87000D03*
X533500Y124500D03*
X534000Y160500D03*
X517000Y212500D03*
X533200Y220000D03*
X529800Y223000D03*
X530350Y257480D03*
X532500Y272500D03*
X532900Y318900D03*
X527600D03*
X532400Y340600D03*
Y345600D03*
X527100Y340600D03*
Y345600D03*
X532200Y377700D03*
X523700Y384100D03*
X528200Y377700D03*
X523700D03*
X525176Y411925D03*
X543957Y60543D03*
X537000Y69000D03*
X534500Y130000D03*
Y136500D03*
X534600Y148300D03*
Y152000D03*
X544000Y159000D03*
X542500Y189500D03*
X538500D03*
X540900Y201500D03*
X543500Y205000D03*
X536900Y201500D03*
X549000Y267500D03*
X551700Y256300D03*
X541346Y303507D03*
X538600Y318900D03*
X538100Y340600D03*
Y345600D03*
X548557Y387700D03*
X538500Y407875D03*
X543000Y396700D03*
X562500Y74600D03*
X560650Y70450D03*
X559941Y62120D03*
X563341Y62102D03*
X564350Y65350D03*
X559000Y85000D03*
X560200Y81500D03*
X559000Y88800D03*
X568700Y204300D03*
X564700Y204400D03*
X553800Y240200D03*
X563700Y352400D03*
X564500Y379000D03*
X560200Y386500D03*
X580500Y65800D03*
X580643Y60900D03*
X585900Y79600D03*
X576459Y161971D03*
X575072Y165500D03*
X580500Y194500D03*
X583000Y192000D03*
X573200Y204300D03*
X586500Y230000D03*
X581500Y267000D03*
X581400Y292250D03*
X580300Y356700D03*
X576300Y371200D03*
X580200Y361700D03*
X580100Y366700D03*
X580300Y380700D03*
Y375700D03*
Y385700D03*
X599000Y92500D03*
X592000Y136000D03*
X597703Y187000D03*
X616500Y194874D03*
X614100Y224100D03*
X610500Y227000D03*
X622000Y136000D03*
X633500Y196874D03*
X636000Y216142D03*
X626989Y237989D03*
X633500Y301500D03*
X647000Y113500D03*
M02*
